FILE_TYPE = MACRO_DRAWING;
SET COLOR_WIRE YELLOW;
SET COLOR_PROP ORANGE;
SET COLOR_DOT WHITE;
SET COLOR_ARC YELLOW;
SET COLOR_BODY GREEN;
SET COLOR_NOTE PURPLE;
SET PROP_DISPLAY VALUE;
SET PAGE_NUMBER P17;
SET PATH_NUMBER P289;
FORCEADD UNIVERSAL_GND..1
(-3900 -650);
FORCEPROP 3 LASTPIN (-3900 -600) SIG_NAME GND\g
J 0
(-3890 -590);
DISPLAY 0.659574 (-3890 -590);
PAINT MONO (-3890 -590);
DISPLAY INVISIBLE (-3890 -590);
FORCEPROP 2 LAST CDS_LIB logical_power
J 0
(-3900 -650);
DISPLAY INVISIBLE (-3900 -650);
FORCEPROP 1 LAST HDL_POWER GND
J 1
(-3875 -725);
DISPLAY 0.702128 (-3875 -725);
PAINT GREEN (-3875 -725);
DISPLAY INVISIBLE (-3875 -725);
FORCEPROP 1 LAST PATH I1
J 0
(-3825 -650);
DISPLAY 0.872340 (-3825 -650);
PAINT AQUA (-3825 -650);
DISPLAY INVISIBLE (-3825 -650);
FORCEADD UNIVERSAL_POWER..1
(4550 3400);
FORCEPROP 3 LASTPIN (4550 3350) SIG_NAME P1V2_P1V0_I3C_VDDL2\g
J 0
(4560 3360);
DISPLAY 0.659574 (4560 3360);
PAINT MONO (4560 3360);
DISPLAY INVISIBLE (4560 3360);
FORCEPROP 1 LAST HDL_POWER P1V2_P1V0_I3C_VDDL2
J 1
(4550 3450);
DISPLAY 0.702128 (4550 3450);
PAINT GREEN (4550 3450);
FORCEPROP 2 LAST CDS_LIB logical_power
J 0
(4550 3400);
DISPLAY INVISIBLE (4550 3400);
FORCEPROP 1 LAST PATH I100
J 0
(4600 3425);
DISPLAY 0.872340 (4600 3425);
PAINT AQUA (4600 3425);
DISPLAY INVISIBLE (4600 3425);
FORCEADD Q_RES..1
(3350 3925);
FORCEPROP 1 LAST VALUE 0
J 2
(3550 3925);
DISPLAY 0.510638 (3550 3925);
PAINT SKYBLUE (3550 3925);
FORCEPROP 1 LAST TOLERANCE 5%
J 0
(3850 4025);
DISPLAY 0.510638 (3850 4025);
PAINT SKYBLUE (3850 4025);
FORCEPROP 1 LAST MATERIAL EMPTY
J 0
(3625 3925);
DISPLAY 0.510638 (3625 3925);
PAINT RED (3625 3925);
FORCEPROP 1 LAST WATTAGE 1/16W
J 2
(3525 4025);
DISPLAY 0.510638 (3525 4025);
PAINT SKYBLUE (3525 4025);
FORCEPROP 1 LAST PACK_TYPE 0402LF
J 0
(3550 4025);
DISPLAY 0.510638 (3550 4025);
PAINT SKYBLUE (3550 4025);
FORCEPROP 1 LAST PART_NUMBER CS00002JB13
J 0
(3350 4100);
DISPLAY 0.510638 (3350 4100);
PAINT WHITE (3350 4100);
FORCEPROP 2 LAST CDS_LIB pure_quanta
J 0
(3350 3925);
DISPLAY INVISIBLE (3350 3925);
FORCEPROP 1 LAST PATH I101
J 0
(3300 4075);
DISPLAY 0.978723 (3300 4075);
PAINT WHITE (3300 4075);
DISPLAY INVISIBLE (3300 4075);
FORCEPROP 1 LAST LOCATION R278
J 0
(3025 3950);
DISPLAY 0.702128 (3025 3950);
PAINT YELLOW (3025 3950);
FORCEPROP 1 LASTPIN (3250 3925) $PN 1
J 0
(3262 3937);
DISPLAY 0.808511 (3262 3937);
PAINT WHITE (3262 3937);
FORCEPROP 1 LASTPIN (3450 3925) $PN 2
J 0
(3412 3937);
DISPLAY 0.808511 (3412 3937);
PAINT WHITE (3412 3937);
FORCEPROP 0 LAST $SEC 1
J 0
(3350 4150);
DISPLAY 0.680851 (3350 4150);
PAINT MONO (3350 4150);
DISPLAY INVISIBLE (3350 4150);
FORCEPROP 0 LAST CDS_SEC 1
J 0
(3350 4150);
DISPLAY 0.680851 (3350 4150);
DISPLAY INVISIBLE (3350 4150);
FORCEADD UNIVERSAL_POWER..1
(2925 4175);
FORCEPROP 3 LASTPIN (2925 4125) SIG_NAME P1V2_AUX\g
J 0
(2935 4135);
DISPLAY 0.659574 (2935 4135);
PAINT MONO (2935 4135);
DISPLAY INVISIBLE (2935 4135);
FORCEPROP 1 LAST HDL_POWER P1V2_AUX
J 1
(2925 4225);
DISPLAY 0.702128 (2925 4225);
PAINT GREEN (2925 4225);
FORCEPROP 2 LAST CDS_LIB logical_power
J 0
(2925 4175);
DISPLAY INVISIBLE (2925 4175);
FORCEPROP 1 LAST PATH I102
J 0
(2975 4200);
DISPLAY 0.872340 (2975 4200);
PAINT AQUA (2975 4200);
DISPLAY INVISIBLE (2975 4200);
FORCEADD UNIVERSAL_GND..1
(75 3175);
FORCEPROP 3 LASTPIN (75 3225) SIG_NAME GND\g
J 0
(85 3235);
DISPLAY 0.659574 (85 3235);
PAINT MONO (85 3235);
DISPLAY INVISIBLE (85 3235);
FORCEPROP 2 LAST CDS_LIB logical_power
J 0
(75 3175);
DISPLAY INVISIBLE (75 3175);
FORCEPROP 1 LAST HDL_POWER GND
J 1
(100 3100);
DISPLAY 0.702128 (100 3100);
PAINT GREEN (100 3100);
DISPLAY INVISIBLE (100 3100);
FORCEPROP 1 LAST PATH I103
J 0
(150 3175);
DISPLAY 0.872340 (150 3175);
PAINT AQUA (150 3175);
DISPLAY INVISIBLE (150 3175);
FORCEADD Q_CAP..2
(350 3300);
FORCEPROP 1 LAST VALUE 0.01UF
J 2
(725 3325);
DISPLAY 0.510638 (725 3325);
PAINT SKYBLUE (725 3325);
FORCEPROP 2 LAST CDS_LIB pure_quanta
J 0
(350 3300);
DISPLAY INVISIBLE (350 3300);
FORCEPROP 1 LAST PART_NUMBER CH31006KB18
J 1
(350 3350);
DISPLAY 0.510638 (350 3350);
PAINT WHITE (350 3350);
DISPLAY INVISIBLE (350 3350);
FORCEPROP 1 LAST VOLTAGE 50V
J 0
(350 3200);
DISPLAY 0.510638 (350 3200);
PAINT SKYBLUE (350 3200);
DISPLAY INVISIBLE (350 3200);
FORCEPROP 1 LAST MATERIAL X7R
J 0
(350 3150);
DISPLAY 0.510638 (350 3150);
PAINT SKYBLUE (350 3150);
DISPLAY INVISIBLE (350 3150);
FORCEPROP 1 LAST TOLERANCE 10%
J 2
(350 3150);
DISPLAY 0.510638 (350 3150);
PAINT SKYBLUE (350 3150);
DISPLAY INVISIBLE (350 3150);
FORCEPROP 1 LAST PACK_TYPE C0402
J 1
(350 3100);
DISPLAY 0.510638 (350 3100);
PAINT SKYBLUE (350 3100);
DISPLAY INVISIBLE (350 3100);
FORCEPROP 1 LAST PATH I104
J 0
(350 3500);
DISPLAY 0.978723 (350 3500);
PAINT WHITE (350 3500);
DISPLAY INVISIBLE (350 3500);
FORCEPROP 1 LAST LOCATION C133
J 1
(175 3300);
DISPLAY 0.702128 (175 3300);
PAINT YELLOW (175 3300);
FORCEPROP 1 LASTPIN (250 3300) $PN 1
J 0
(240 3315);
DISPLAY 0.808511 (240 3315);
PAINT WHITE (240 3315);
FORCEPROP 1 LASTPIN (450 3300) $PN 2
J 0
(435 3315);
DISPLAY 0.808511 (435 3315);
PAINT WHITE (435 3315);
FORCEPROP 2 LAST $SEC 1
J 0
(350 3550);
DISPLAY 0.680851 (350 3550);
PAINT MONO (350 3550);
DISPLAY INVISIBLE (350 3550);
FORCEPROP 0 LAST CDS_SEC 1
J 0
(350 3550);
DISPLAY 0.680851 (350 3550);
PAINT MONO (350 3550);
DISPLAY INVISIBLE (350 3550);
FORCEADD UNIVERSAL_GND..1
(125 3775);
FORCEPROP 3 LASTPIN (125 3825) SIG_NAME GND\g
J 0
(135 3835);
DISPLAY 0.659574 (135 3835);
PAINT MONO (135 3835);
DISPLAY INVISIBLE (135 3835);
FORCEPROP 2 LAST CDS_LIB logical_power
J 0
(125 3775);
DISPLAY INVISIBLE (125 3775);
FORCEPROP 1 LAST HDL_POWER GND
J 1
(150 3700);
DISPLAY 0.702128 (150 3700);
PAINT GREEN (150 3700);
DISPLAY INVISIBLE (150 3700);
FORCEPROP 1 LAST PATH I105
J 0
(200 3775);
DISPLAY 0.872340 (200 3775);
PAINT AQUA (200 3775);
DISPLAY INVISIBLE (200 3775);
FORCEADD Q_CAP..2
(400 3900);
FORCEPROP 1 LAST VALUE 0.01UF
J 2
(775 3925);
DISPLAY 0.510638 (775 3925);
PAINT SKYBLUE (775 3925);
FORCEPROP 2 LAST CDS_LIB pure_quanta
J 0
(400 3900);
DISPLAY INVISIBLE (400 3900);
FORCEPROP 1 LAST PART_NUMBER CH31006KB18
J 1
(400 3950);
DISPLAY 0.510638 (400 3950);
PAINT WHITE (400 3950);
DISPLAY INVISIBLE (400 3950);
FORCEPROP 1 LAST VOLTAGE 50V
J 0
(400 3800);
DISPLAY 0.510638 (400 3800);
PAINT SKYBLUE (400 3800);
DISPLAY INVISIBLE (400 3800);
FORCEPROP 1 LAST MATERIAL X7R
J 0
(400 3750);
DISPLAY 0.510638 (400 3750);
PAINT SKYBLUE (400 3750);
DISPLAY INVISIBLE (400 3750);
FORCEPROP 1 LAST TOLERANCE 10%
J 2
(400 3750);
DISPLAY 0.510638 (400 3750);
PAINT SKYBLUE (400 3750);
DISPLAY INVISIBLE (400 3750);
FORCEPROP 1 LAST PACK_TYPE C0402
J 1
(400 3700);
DISPLAY 0.510638 (400 3700);
PAINT SKYBLUE (400 3700);
DISPLAY INVISIBLE (400 3700);
FORCEPROP 1 LAST PATH I106
J 0
(400 4100);
DISPLAY 0.978723 (400 4100);
PAINT WHITE (400 4100);
DISPLAY INVISIBLE (400 4100);
FORCEPROP 1 LAST LOCATION C134
J 1
(225 3900);
DISPLAY 0.702128 (225 3900);
PAINT YELLOW (225 3900);
FORCEPROP 1 LASTPIN (300 3900) $PN 1
J 0
(290 3915);
DISPLAY 0.808511 (290 3915);
PAINT WHITE (290 3915);
FORCEPROP 1 LASTPIN (500 3900) $PN 2
J 0
(485 3915);
DISPLAY 0.808511 (485 3915);
PAINT WHITE (485 3915);
FORCEPROP 0 LAST $SEC 1
J 0
(775 3975);
DISPLAY 0.680851 (775 3975);
PAINT MONO (775 3975);
DISPLAY INVISIBLE (775 3975);
FORCEPROP 0 LAST CDS_SEC 1
J 0
(775 3975);
DISPLAY 0.680851 (775 3975);
DISPLAY INVISIBLE (775 3975);
FORCEADD Q_CAP..2
(775 3425);
FORCEPROP 1 LAST PART_NUMBER CH31006KB18
J 1
(850 3625);
DISPLAY 0.510638 (850 3625);
PAINT WHITE (850 3625);
FORCEPROP 1 LAST VALUE 0.01UF
J 2
(1225 3450);
DISPLAY 0.510638 (1225 3450);
PAINT SKYBLUE (1225 3450);
FORCEPROP 1 LAST VOLTAGE 50V
J 0
(1125 3575);
DISPLAY 0.510638 (1125 3575);
PAINT SKYBLUE (1125 3575);
FORCEPROP 1 LAST TOLERANCE 10%
J 2
(1100 3575);
DISPLAY 0.510638 (1100 3575);
PAINT SKYBLUE (1100 3575);
FORCEPROP 1 LAST PACK_TYPE C0402
J 1
(675 3575);
DISPLAY 0.510638 (675 3575);
PAINT SKYBLUE (675 3575);
FORCEPROP 1 LAST MATERIAL X7R
J 0
(825 3575);
DISPLAY 0.510638 (825 3575);
PAINT SKYBLUE (825 3575);
FORCEPROP 2 LAST CDS_LIB pure_quanta
J 0
(775 3425);
DISPLAY INVISIBLE (775 3425);
FORCEPROP 1 LAST PATH I107
J 0
(775 3625);
DISPLAY 0.978723 (775 3625);
PAINT WHITE (775 3625);
DISPLAY INVISIBLE (775 3625);
FORCEPROP 1 LAST LOCATION C135
J 1
(575 3450);
DISPLAY 0.702128 (575 3450);
PAINT YELLOW (575 3450);
FORCEPROP 1 LASTPIN (675 3425) $PN 1
J 0
(665 3440);
DISPLAY 0.808511 (665 3440);
PAINT WHITE (665 3440);
FORCEPROP 1 LASTPIN (875 3425) $PN 2
J 0
(860 3440);
DISPLAY 0.808511 (860 3440);
PAINT WHITE (860 3440);
FORCEPROP 0 LAST $SEC 1
J 0
(850 3675);
DISPLAY 0.680851 (850 3675);
PAINT MONO (850 3675);
DISPLAY INVISIBLE (850 3675);
FORCEPROP 0 LAST CDS_SEC 1
J 0
(850 3675);
DISPLAY 0.680851 (850 3675);
DISPLAY INVISIBLE (850 3675);
FORCEADD Q_CAP..2
(1000 3300);
FORCEPROP 1 LAST VALUE 0.01UF
J 2
(1375 3325);
DISPLAY 0.510638 (1375 3325);
PAINT SKYBLUE (1375 3325);
FORCEPROP 2 LAST CDS_LIB pure_quanta
J 0
(1000 3300);
DISPLAY INVISIBLE (1000 3300);
FORCEPROP 1 LAST PART_NUMBER CH31006KB18
J 1
(1000 3350);
DISPLAY 0.510638 (1000 3350);
PAINT WHITE (1000 3350);
DISPLAY INVISIBLE (1000 3350);
FORCEPROP 1 LAST VOLTAGE 50V
J 0
(1000 3200);
DISPLAY 0.510638 (1000 3200);
PAINT SKYBLUE (1000 3200);
DISPLAY INVISIBLE (1000 3200);
FORCEPROP 1 LAST MATERIAL X7R
J 0
(1000 3150);
DISPLAY 0.510638 (1000 3150);
PAINT SKYBLUE (1000 3150);
DISPLAY INVISIBLE (1000 3150);
FORCEPROP 1 LAST TOLERANCE 10%
J 2
(1000 3150);
DISPLAY 0.510638 (1000 3150);
PAINT SKYBLUE (1000 3150);
DISPLAY INVISIBLE (1000 3150);
FORCEPROP 1 LAST PACK_TYPE C0402
J 1
(1000 3100);
DISPLAY 0.510638 (1000 3100);
PAINT SKYBLUE (1000 3100);
DISPLAY INVISIBLE (1000 3100);
FORCEPROP 1 LAST PATH I108
J 0
(1000 3500);
DISPLAY 0.978723 (1000 3500);
PAINT WHITE (1000 3500);
DISPLAY INVISIBLE (1000 3500);
FORCEPROP 1 LAST LOCATION C137
J 1
(825 3325);
DISPLAY 0.702128 (825 3325);
PAINT YELLOW (825 3325);
FORCEPROP 1 LASTPIN (900 3300) $PN 1
J 0
(890 3315);
DISPLAY 0.808511 (890 3315);
PAINT WHITE (890 3315);
FORCEPROP 1 LASTPIN (1100 3300) $PN 2
J 0
(1085 3315);
DISPLAY 0.808511 (1085 3315);
PAINT WHITE (1085 3315);
FORCEPROP 0 LAST $SEC 1
J 0
(1375 3375);
DISPLAY 0.680851 (1375 3375);
PAINT MONO (1375 3375);
DISPLAY INVISIBLE (1375 3375);
FORCEPROP 0 LAST CDS_SEC 1
J 0
(1375 3375);
DISPLAY 0.680851 (1375 3375);
DISPLAY INVISIBLE (1375 3375);
FORCEADD Q_CAP..2
(1050 3900);
FORCEPROP 1 LAST VALUE 0.01UF
J 2
(1425 3925);
DISPLAY 0.510638 (1425 3925);
PAINT SKYBLUE (1425 3925);
FORCEPROP 2 LAST CDS_LIB pure_quanta
J 0
(1050 3900);
DISPLAY INVISIBLE (1050 3900);
FORCEPROP 1 LAST PART_NUMBER CH31006KB18
J 1
(1050 3950);
DISPLAY 0.510638 (1050 3950);
PAINT WHITE (1050 3950);
DISPLAY INVISIBLE (1050 3950);
FORCEPROP 1 LAST VOLTAGE 50V
J 0
(1050 3800);
DISPLAY 0.510638 (1050 3800);
PAINT SKYBLUE (1050 3800);
DISPLAY INVISIBLE (1050 3800);
FORCEPROP 1 LAST MATERIAL X7R
J 0
(1050 3750);
DISPLAY 0.510638 (1050 3750);
PAINT SKYBLUE (1050 3750);
DISPLAY INVISIBLE (1050 3750);
FORCEPROP 1 LAST TOLERANCE 10%
J 2
(1050 3750);
DISPLAY 0.510638 (1050 3750);
PAINT SKYBLUE (1050 3750);
DISPLAY INVISIBLE (1050 3750);
FORCEPROP 1 LAST PACK_TYPE C0402
J 1
(1050 3700);
DISPLAY 0.510638 (1050 3700);
PAINT SKYBLUE (1050 3700);
DISPLAY INVISIBLE (1050 3700);
FORCEPROP 1 LAST PATH I109
J 0
(1050 4100);
DISPLAY 0.978723 (1050 4100);
PAINT WHITE (1050 4100);
DISPLAY INVISIBLE (1050 4100);
FORCEPROP 1 LAST LOCATION C138
J 1
(875 3900);
DISPLAY 0.702128 (875 3900);
PAINT YELLOW (875 3900);
FORCEPROP 1 LASTPIN (950 3900) $PN 1
J 0
(940 3915);
DISPLAY 0.808511 (940 3915);
PAINT WHITE (940 3915);
FORCEPROP 1 LASTPIN (1150 3900) $PN 2
J 0
(1135 3915);
DISPLAY 0.808511 (1135 3915);
PAINT WHITE (1135 3915);
FORCEPROP 2 LAST $SEC 1
J 0
(1050 4150);
DISPLAY 0.680851 (1050 4150);
PAINT MONO (1050 4150);
DISPLAY INVISIBLE (1050 4150);
FORCEPROP 0 LAST CDS_SEC 1
J 0
(1050 4150);
DISPLAY 0.680851 (1050 4150);
PAINT MONO (1050 4150);
DISPLAY INVISIBLE (1050 4150);
FORCEADD Q_CAP..2
(825 4025);
FORCEPROP 1 LAST PART_NUMBER CH31006KB18
J 1
(900 4175);
DISPLAY 0.510638 (900 4175);
PAINT WHITE (900 4175);
FORCEPROP 1 LAST VOLTAGE 50V
J 0
(1150 4125);
DISPLAY 0.510638 (1150 4125);
PAINT SKYBLUE (1150 4125);
FORCEPROP 1 LAST MATERIAL X7R
J 0
(875 4125);
DISPLAY 0.510638 (875 4125);
PAINT SKYBLUE (875 4125);
FORCEPROP 1 LAST TOLERANCE 10%
J 2
(1125 4125);
DISPLAY 0.510638 (1125 4125);
PAINT SKYBLUE (1125 4125);
FORCEPROP 1 LAST PACK_TYPE C0402
J 1
(725 4125);
DISPLAY 0.510638 (725 4125);
PAINT SKYBLUE (725 4125);
FORCEPROP 1 LAST VALUE 0.01UF
J 2
(1200 4050);
DISPLAY 0.510638 (1200 4050);
PAINT SKYBLUE (1200 4050);
FORCEPROP 2 LAST CDS_LIB pure_quanta
J 0
(825 4025);
DISPLAY INVISIBLE (825 4025);
FORCEPROP 1 LAST PATH I110
J 0
(825 4225);
DISPLAY 0.978723 (825 4225);
PAINT WHITE (825 4225);
DISPLAY INVISIBLE (825 4225);
FORCEPROP 1 LAST LOCATION C136
J 1
(600 4050);
DISPLAY 0.702128 (600 4050);
PAINT YELLOW (600 4050);
FORCEPROP 1 LASTPIN (725 4025) $PN 1
J 0
(715 4040);
DISPLAY 0.808511 (715 4040);
PAINT WHITE (715 4040);
FORCEPROP 1 LASTPIN (925 4025) $PN 2
J 0
(910 4040);
DISPLAY 0.808511 (910 4040);
PAINT WHITE (910 4040);
FORCEPROP 2 LAST $SEC 1
J 0
(825 4275);
DISPLAY 0.680851 (825 4275);
PAINT MONO (825 4275);
DISPLAY INVISIBLE (825 4275);
FORCEPROP 0 LAST CDS_SEC 1
J 0
(825 4275);
DISPLAY 0.680851 (825 4275);
PAINT MONO (825 4275);
DISPLAY INVISIBLE (825 4275);
FORCEADD UNIVERSAL_POWER..1
(4550 4150);
FORCEPROP 3 LASTPIN (4550 4100) SIG_NAME P1V2_P1V0_I3C_VDDL1\g
J 0
(4560 4110);
DISPLAY 0.659574 (4560 4110);
PAINT MONO (4560 4110);
DISPLAY INVISIBLE (4560 4110);
FORCEPROP 1 LAST HDL_POWER P1V2_P1V0_I3C_VDDL1
J 1
(4550 4200);
DISPLAY 0.702128 (4550 4200);
PAINT GREEN (4550 4200);
FORCEPROP 2 LAST CDS_LIB logical_power
J 0
(4550 4150);
DISPLAY INVISIBLE (4550 4150);
FORCEPROP 1 LAST PATH I111
J 0
(4600 4175);
DISPLAY 0.872340 (4600 4175);
PAINT AQUA (4600 4175);
DISPLAY INVISIBLE (4600 4175);
FORCEADD OFFPAGE..4
(2000 3300);
FORCEPROP 2 LAST $XR0 16 
J 0
(2186 3300);
DISPLAY 0.638298 (2186 3300);
PAINT MONO (2186 3300);
FORCEPROP 2 LAST CDS_LIB standard
J 0
(2000 3300);
DISPLAY INVISIBLE (2000 3300);
FORCEPROP 1 LAST OFFPAGE TRUE
J 0
(2325 3175);
DISPLAY 1.574468 (2325 3175);
PAINT GREEN (2325 3175);
DISPLAY INVISIBLE (2325 3175);
FORCEPROP 1 LAST COMMENT_BODY TRUE
J 0
(1975 3200);
DISPLAY 1.574468 (1975 3200);
PAINT PEACH (1975 3200);
DISPLAY INVISIBLE (1975 3200);
FORCEPROP 2 LAST PATH I112
J 0
(2200 3350);
DISPLAY 1.021277 (2200 3350);
DISPLAY INVISIBLE (2200 3350);
FORCEADD OFFPAGE..4
(2000 3225);
FORCEPROP 2 LAST $XR0 16 
J 0
(2186 3225);
DISPLAY 0.638298 (2186 3225);
PAINT MONO (2186 3225);
FORCEPROP 2 LAST CDS_LIB standard
J 0
(2000 3225);
DISPLAY INVISIBLE (2000 3225);
FORCEPROP 1 LAST OFFPAGE TRUE
J 0
(2325 3100);
DISPLAY 1.574468 (2325 3100);
PAINT GREEN (2325 3100);
DISPLAY INVISIBLE (2325 3100);
FORCEPROP 1 LAST COMMENT_BODY TRUE
J 0
(1975 3125);
DISPLAY 1.574468 (1975 3125);
PAINT PEACH (1975 3125);
DISPLAY INVISIBLE (1975 3125);
FORCEPROP 2 LAST PATH I113
J 0
(2200 3275);
DISPLAY 1.021277 (2200 3275);
DISPLAY INVISIBLE (2200 3275);
FORCEADD OFFPAGE..4
(2050 3825);
FORCEPROP 2 LAST $XR0 16 
J 0
(2236 3825);
DISPLAY 0.638298 (2236 3825);
PAINT MONO (2236 3825);
FORCEPROP 2 LAST CDS_LIB standard
J 0
(2050 3825);
DISPLAY INVISIBLE (2050 3825);
FORCEPROP 1 LAST OFFPAGE TRUE
J 0
(2375 3700);
DISPLAY 1.574468 (2375 3700);
PAINT GREEN (2375 3700);
DISPLAY INVISIBLE (2375 3700);
FORCEPROP 1 LAST COMMENT_BODY TRUE
J 0
(2025 3725);
DISPLAY 1.574468 (2025 3725);
PAINT PEACH (2025 3725);
DISPLAY INVISIBLE (2025 3725);
FORCEPROP 2 LAST PATH I114
J 0
(2250 3875);
DISPLAY 1.021277 (2250 3875);
DISPLAY INVISIBLE (2250 3875);
FORCEADD OFFPAGE..4
(2050 3900);
FORCEPROP 2 LAST $XR0 16 
J 0
(2236 3900);
DISPLAY 0.638298 (2236 3900);
PAINT MONO (2236 3900);
FORCEPROP 2 LAST CDS_LIB standard
J 0
(2050 3900);
DISPLAY INVISIBLE (2050 3900);
FORCEPROP 1 LAST OFFPAGE TRUE
J 0
(2375 3775);
DISPLAY 1.574468 (2375 3775);
PAINT GREEN (2375 3775);
DISPLAY INVISIBLE (2375 3775);
FORCEPROP 1 LAST COMMENT_BODY TRUE
J 0
(2025 3800);
DISPLAY 1.574468 (2025 3800);
PAINT PEACH (2025 3800);
DISPLAY INVISIBLE (2025 3800);
FORCEPROP 2 LAST PATH I115
J 0
(2250 3950);
DISPLAY 1.021277 (2250 3950);
DISPLAY INVISIBLE (2250 3950);
FORCEADD Q_CAP..1
(-925 3875);
FORCEPROP 1 LAST PART_NUMBER CH4104K1B00
J 0
(-875 3675);
DISPLAY 0.510638 (-875 3675);
PAINT WHITE (-875 3675);
FORCEPROP 1 LAST VOLTAGE 25V
J 0
(-875 3875);
DISPLAY 0.510638 (-875 3875);
PAINT SKYBLUE (-875 3875);
FORCEPROP 1 LAST MATERIAL X7R
J 0
(-875 3775);
DISPLAY 0.510638 (-875 3775);
PAINT SKYBLUE (-875 3775);
FORCEPROP 1 LAST TOLERANCE 10%
J 0
(-875 3825);
DISPLAY 0.510638 (-875 3825);
PAINT SKYBLUE (-875 3825);
FORCEPROP 1 LAST VALUE 0.1UF
J 0
(-875 3925);
DISPLAY 0.510638 (-875 3925);
PAINT SKYBLUE (-875 3925);
FORCEPROP 1 LAST PACK_TYPE 0402
J 0
(-875 3725);
DISPLAY 0.510638 (-875 3725);
PAINT SKYBLUE (-875 3725);
FORCEPROP 2 LAST CDS_LIB pure_quanta
J 0
(-925 3875);
DISPLAY INVISIBLE (-925 3875);
FORCEPROP 1 LAST PATH I118
J 0
(-875 4025);
DISPLAY 0.978723 (-875 4025);
PAINT WHITE (-875 4025);
DISPLAY INVISIBLE (-875 4025);
FORCEPROP 1 LAST LOCATION C49
J 0
(-875 3975);
DISPLAY 0.702128 (-875 3975);
PAINT YELLOW (-875 3975);
FORCEPROP 1 LASTPIN (-925 3975) $PN 1
J 0
(-915 3955);
DISPLAY 0.808511 (-915 3955);
PAINT WHITE (-915 3955);
FORCEPROP 1 LASTPIN (-925 3775) $PN 2
J 0
(-915 3755);
DISPLAY 0.808511 (-915 3755);
PAINT WHITE (-915 3755);
FORCEPROP 2 LAST $SEC 1
J 0
(-875 4075);
DISPLAY 0.680851 (-875 4075);
PAINT MONO (-875 4075);
DISPLAY INVISIBLE (-875 4075);
FORCEPROP 0 LAST CDS_SEC 1
J 0
(-875 4075);
DISPLAY 0.680851 (-875 4075);
PAINT MONO (-875 4075);
DISPLAY INVISIBLE (-875 4075);
FORCEADD OFFPAGE..2
(-425 3175);
FORCEPROP 2 LAST $XR0 16 
J 0
(-236 3175);
DISPLAY 0.638298 (-236 3175);
PAINT MONO (-236 3175);
FORCEPROP 2 LAST CDS_LIB standard
J 0
(-425 3175);
DISPLAY INVISIBLE (-425 3175);
FORCEPROP 1 LAST OFFPAGE TRUE
J 0
(-100 3050);
DISPLAY 0.872340 (-100 3050);
PAINT GREEN (-100 3050);
DISPLAY INVISIBLE (-100 3050);
FORCEPROP 1 LAST COMMENT_BODY TRUE
J 0
(-470 3080);
DISPLAY 0.872340 (-470 3080);
PAINT PEACH (-470 3080);
DISPLAY INVISIBLE (-470 3080);
FORCEPROP 2 LAST PATH I119
J 0
(-175 3225);
DISPLAY 1.021277 (-175 3225);
DISPLAY INVISIBLE (-175 3225);
FORCEADD Q_INDUCTOR..1
(-1425 4075);
FORCEPROP 1 LAST PART_NUMBER CX8PG121009
J 0
(-1550 4185);
DISPLAY 0.510638 (-1550 4185);
PAINT WHITE (-1550 4185);
FORCEPROP 1 LAST MATERIAL IND
J 0
(-1550 4130);
DISPLAY 0.510638 (-1550 4130);
PAINT SKYBLUE (-1550 4130);
FORCEPROP 2 LAST VALUE BLM18PG121SN1D/2000MA
J 0
(-1550 4325);
DISPLAY 0.510638 (-1550 4325);
PAINT SKYBLUE (-1550 4325);
FORCEPROP 2 LAST PACK_TYPE SMLF
J 0
(-1550 4275);
DISPLAY 0.510638 (-1550 4275);
PAINT SKYBLUE (-1550 4275);
FORCEPROP 2 LAST CDS_LIB pure_quanta
J 0
(-1425 4075);
DISPLAY INVISIBLE (-1425 4075);
FORCEPROP 1 LAST NEEDS_NO_SIZE TRUE
J 0
(-1425 4075);
DISPLAY 0.468085 (-1425 4075);
PAINT GREEN (-1425 4075);
DISPLAY INVISIBLE (-1425 4075);
FORCEPROP 1 LAST PATH I120
J 0
(-1350 4130);
DISPLAY 0.723404 (-1350 4130);
PAINT GREEN (-1350 4130);
DISPLAY INVISIBLE (-1350 4130);
FORCEPROP 1 LAST LOCATION L5
J 0
(-1550 4235);
DISPLAY 0.702128 (-1550 4235);
PAINT YELLOW (-1550 4235);
FORCEPROP 2 LASTPIN (-1525 4050) $PN 1
J 2
(-1535 4060);
DISPLAY 0.808511 (-1535 4060);
PAINT WHITE (-1535 4060);
FORCEPROP 2 LASTPIN (-1325 4050) $PN 2
J 0
(-1315 4060);
DISPLAY 0.808511 (-1315 4060);
PAINT WHITE (-1315 4060);
FORCEPROP 2 LAST $SEC 1
J 0
(-1550 4375);
DISPLAY 0.680851 (-1550 4375);
PAINT MONO (-1550 4375);
DISPLAY INVISIBLE (-1550 4375);
FORCEPROP 0 LAST CDS_SEC 1
J 0
(-1550 4375);
DISPLAY 0.680851 (-1550 4375);
PAINT MONO (-1550 4375);
DISPLAY INVISIBLE (-1550 4375);
FORCEADD UNIVERSAL_POWER..1
(-1725 4125);
FORCEPROP 3 LASTPIN (-1725 4075) SIG_NAME P1V8_AUX\g
J 0
(-1715 4085);
DISPLAY 0.659574 (-1715 4085);
PAINT MONO (-1715 4085);
DISPLAY INVISIBLE (-1715 4085);
FORCEPROP 1 LAST HDL_POWER P1V8_AUX
J 1
(-1725 4175);
DISPLAY 0.702128 (-1725 4175);
PAINT GREEN (-1725 4175);
FORCEPROP 2 LAST CDS_LIB logical_power
J 0
(-1725 4125);
DISPLAY INVISIBLE (-1725 4125);
FORCEPROP 1 LAST PATH I121
J 0
(-1675 4150);
DISPLAY 0.872340 (-1675 4150);
PAINT AQUA (-1675 4150);
DISPLAY INVISIBLE (-1675 4150);
FORCEADD Q_CAP..1
(-1125 3875);
FORCEPROP 1 LAST PART_NUMBER CH5104KEB02
R 3
J 0
(-1225 4000);
DISPLAY 0.510638 (-1225 4000);
PAINT WHITE (-1225 4000);
FORCEPROP 1 LAST VOLTAGE 25V
J 0
(-1075 3875);
DISPLAY 0.510638 (-1075 3875);
PAINT SKYBLUE (-1075 3875);
FORCEPROP 1 LAST TOLERANCE 10%
J 0
(-1075 3825);
DISPLAY 0.510638 (-1075 3825);
PAINT SKYBLUE (-1075 3825);
FORCEPROP 1 LAST MATERIAL X6S
J 0
(-1075 3775);
DISPLAY 0.510638 (-1075 3775);
PAINT SKYBLUE (-1075 3775);
FORCEPROP 1 LAST PACK_TYPE C0402
J 0
(-1100 3725);
DISPLAY 0.510638 (-1100 3725);
PAINT SKYBLUE (-1100 3725);
FORCEPROP 1 LAST VALUE 1UF
J 0
(-1075 3925);
DISPLAY 0.510638 (-1075 3925);
PAINT SKYBLUE (-1075 3925);
FORCEPROP 2 LAST CDS_LIB pure_quanta
J 0
(-1125 3875);
DISPLAY INVISIBLE (-1125 3875);
FORCEPROP 1 LAST PATH I122
J 0
(-1075 4025);
DISPLAY 0.978723 (-1075 4025);
PAINT WHITE (-1075 4025);
DISPLAY INVISIBLE (-1075 4025);
FORCEPROP 1 LAST LOCATION C46
J 0
(-1075 3975);
DISPLAY 0.702128 (-1075 3975);
PAINT YELLOW (-1075 3975);
FORCEPROP 1 LASTPIN (-1125 3975) $PN 1
J 0
(-1115 3955);
DISPLAY 0.808511 (-1115 3955);
PAINT WHITE (-1115 3955);
FORCEPROP 1 LASTPIN (-1125 3775) $PN 2
J 0
(-1115 3755);
DISPLAY 0.808511 (-1115 3755);
PAINT WHITE (-1115 3755);
FORCEPROP 2 LAST $SEC 1
J 0
(-1075 4075);
DISPLAY 0.680851 (-1075 4075);
PAINT MONO (-1075 4075);
DISPLAY INVISIBLE (-1075 4075);
FORCEPROP 0 LAST CDS_SEC 1
J 0
(-1075 4075);
DISPLAY 0.680851 (-1075 4075);
PAINT MONO (-1075 4075);
DISPLAY INVISIBLE (-1075 4075);
FORCEADD UNIVERSAL_GND..1
(-1025 3600);
FORCEPROP 3 LASTPIN (-1025 3650) SIG_NAME GND\g
J 0
(-1015 3660);
DISPLAY 0.659574 (-1015 3660);
PAINT MONO (-1015 3660);
DISPLAY INVISIBLE (-1015 3660);
FORCEPROP 2 LAST CDS_LIB logical_power
J 0
(-1025 3600);
DISPLAY INVISIBLE (-1025 3600);
FORCEPROP 1 LAST HDL_POWER GND
J 1
(-1000 3525);
DISPLAY 0.702128 (-1000 3525);
PAINT GREEN (-1000 3525);
DISPLAY INVISIBLE (-1000 3525);
FORCEPROP 1 LAST PATH I123
J 0
(-950 3600);
DISPLAY 0.872340 (-950 3600);
PAINT AQUA (-950 3600);
DISPLAY INVISIBLE (-950 3600);
FORCEADD Q_INDUCTOR..1
(-1400 3200);
FORCEPROP 2 LAST VALUE BLM18PG121SN1D/2000MA
J 0
(-1525 3450);
DISPLAY 0.510638 (-1525 3450);
PAINT SKYBLUE (-1525 3450);
FORCEPROP 2 LAST PACK_TYPE SMLF
J 0
(-1525 3400);
DISPLAY 0.510638 (-1525 3400);
PAINT SKYBLUE (-1525 3400);
FORCEPROP 1 LAST MATERIAL IND
J 0
(-1525 3255);
DISPLAY 0.510638 (-1525 3255);
PAINT SKYBLUE (-1525 3255);
FORCEPROP 1 LAST PART_NUMBER CX8PG121009
J 0
(-1525 3310);
DISPLAY 0.510638 (-1525 3310);
PAINT WHITE (-1525 3310);
FORCEPROP 2 LAST CDS_LIB pure_quanta
J 0
(-1400 3200);
DISPLAY INVISIBLE (-1400 3200);
FORCEPROP 1 LAST NEEDS_NO_SIZE TRUE
J 0
(-1400 3200);
DISPLAY 0.468085 (-1400 3200);
PAINT GREEN (-1400 3200);
DISPLAY INVISIBLE (-1400 3200);
FORCEPROP 1 LAST PATH I124
J 0
(-1325 3255);
DISPLAY 0.723404 (-1325 3255);
PAINT GREEN (-1325 3255);
DISPLAY INVISIBLE (-1325 3255);
FORCEPROP 1 LAST LOCATION L6
J 0
(-1525 3360);
DISPLAY 0.702128 (-1525 3360);
PAINT YELLOW (-1525 3360);
FORCEPROP 2 LASTPIN (-1500 3175) $PN 1
J 2
(-1510 3185);
DISPLAY 0.808511 (-1510 3185);
PAINT WHITE (-1510 3185);
FORCEPROP 2 LASTPIN (-1300 3175) $PN 2
J 0
(-1290 3185);
DISPLAY 0.808511 (-1290 3185);
PAINT WHITE (-1290 3185);
FORCEPROP 2 LAST $SEC 1
J 0
(-1525 3500);
DISPLAY 0.680851 (-1525 3500);
PAINT MONO (-1525 3500);
DISPLAY INVISIBLE (-1525 3500);
FORCEPROP 0 LAST CDS_SEC 1
J 0
(-1525 3500);
DISPLAY 0.680851 (-1525 3500);
PAINT MONO (-1525 3500);
DISPLAY INVISIBLE (-1525 3500);
FORCEADD UNIVERSAL_POWER..1
(-1700 3250);
FORCEPROP 3 LASTPIN (-1700 3200) SIG_NAME P1V0_AUX\g
J 0
(-1690 3210);
DISPLAY 0.659574 (-1690 3210);
PAINT MONO (-1690 3210);
DISPLAY INVISIBLE (-1690 3210);
FORCEPROP 1 LAST HDL_POWER P1V0_AUX
J 1
(-1700 3300);
DISPLAY 0.702128 (-1700 3300);
PAINT GREEN (-1700 3300);
FORCEPROP 2 LAST CDS_LIB logical_power
J 0
(-1700 3250);
DISPLAY INVISIBLE (-1700 3250);
FORCEPROP 1 LAST PATH I125
J 0
(-1650 3275);
DISPLAY 0.872340 (-1650 3275);
PAINT AQUA (-1650 3275);
DISPLAY INVISIBLE (-1650 3275);
FORCEADD Q_CAP..1
(-900 3000);
FORCEPROP 1 LAST VALUE 0.1UF
J 0
(-850 3050);
DISPLAY 0.510638 (-850 3050);
PAINT SKYBLUE (-850 3050);
FORCEPROP 1 LAST VOLTAGE 25V
J 0
(-850 3000);
DISPLAY 0.510638 (-850 3000);
PAINT SKYBLUE (-850 3000);
FORCEPROP 1 LAST PART_NUMBER CH4104K1B00
J 0
(-850 2800);
DISPLAY 0.510638 (-850 2800);
PAINT WHITE (-850 2800);
FORCEPROP 1 LAST MATERIAL X7R
J 0
(-850 2900);
DISPLAY 0.510638 (-850 2900);
PAINT SKYBLUE (-850 2900);
FORCEPROP 1 LAST TOLERANCE 10%
J 0
(-850 2950);
DISPLAY 0.510638 (-850 2950);
PAINT SKYBLUE (-850 2950);
FORCEPROP 1 LAST PACK_TYPE 0402
J 0
(-850 2850);
DISPLAY 0.510638 (-850 2850);
PAINT SKYBLUE (-850 2850);
FORCEPROP 2 LAST CDS_LIB pure_quanta
J 0
(-900 3000);
DISPLAY INVISIBLE (-900 3000);
FORCEPROP 1 LAST PATH I126
J 0
(-850 3150);
DISPLAY 0.978723 (-850 3150);
PAINT WHITE (-850 3150);
DISPLAY INVISIBLE (-850 3150);
FORCEPROP 1 LAST LOCATION C50
J 0
(-850 3100);
DISPLAY 0.702128 (-850 3100);
PAINT YELLOW (-850 3100);
FORCEPROP 1 LASTPIN (-900 3100) $PN 1
J 0
(-890 3080);
DISPLAY 0.808511 (-890 3080);
PAINT WHITE (-890 3080);
FORCEPROP 1 LASTPIN (-900 2900) $PN 2
J 0
(-890 2880);
DISPLAY 0.808511 (-890 2880);
PAINT WHITE (-890 2880);
FORCEPROP 2 LAST $SEC 1
J 0
(-850 3200);
DISPLAY 0.680851 (-850 3200);
PAINT MONO (-850 3200);
DISPLAY INVISIBLE (-850 3200);
FORCEPROP 0 LAST CDS_SEC 1
J 0
(-850 3200);
DISPLAY 0.680851 (-850 3200);
PAINT MONO (-850 3200);
DISPLAY INVISIBLE (-850 3200);
FORCEADD UNIVERSAL_GND..1
(-1000 2725);
FORCEPROP 3 LASTPIN (-1000 2775) SIG_NAME GND\g
J 0
(-990 2785);
DISPLAY 0.659574 (-990 2785);
PAINT MONO (-990 2785);
DISPLAY INVISIBLE (-990 2785);
FORCEPROP 2 LAST CDS_LIB logical_power
J 0
(-1000 2725);
DISPLAY INVISIBLE (-1000 2725);
FORCEPROP 1 LAST HDL_POWER GND
J 1
(-975 2650);
DISPLAY 0.702128 (-975 2650);
PAINT GREEN (-975 2650);
DISPLAY INVISIBLE (-975 2650);
FORCEPROP 1 LAST PATH I127
J 0
(-925 2725);
DISPLAY 0.872340 (-925 2725);
PAINT AQUA (-925 2725);
DISPLAY INVISIBLE (-925 2725);
FORCEADD Q_CAP..1
(-1100 3000);
FORCEPROP 1 LAST PACK_TYPE C0402
J 0
(-1075 2850);
DISPLAY 0.510638 (-1075 2850);
PAINT SKYBLUE (-1075 2850);
FORCEPROP 1 LAST VOLTAGE 25V
J 0
(-1050 3000);
DISPLAY 0.510638 (-1050 3000);
PAINT SKYBLUE (-1050 3000);
FORCEPROP 1 LAST VALUE 1UF
J 0
(-1050 3050);
DISPLAY 0.510638 (-1050 3050);
PAINT SKYBLUE (-1050 3050);
FORCEPROP 1 LAST PART_NUMBER CH5104KEB02
R 3
J 0
(-1200 3150);
DISPLAY 0.510638 (-1200 3150);
PAINT WHITE (-1200 3150);
FORCEPROP 1 LAST MATERIAL X6S
J 0
(-1050 2900);
DISPLAY 0.510638 (-1050 2900);
PAINT SKYBLUE (-1050 2900);
FORCEPROP 1 LAST TOLERANCE 10%
J 0
(-1050 2950);
DISPLAY 0.510638 (-1050 2950);
PAINT SKYBLUE (-1050 2950);
FORCEPROP 2 LAST CDS_LIB pure_quanta
J 0
(-1100 3000);
DISPLAY INVISIBLE (-1100 3000);
FORCEPROP 1 LAST PATH I128
J 0
(-1050 3150);
DISPLAY 0.978723 (-1050 3150);
PAINT WHITE (-1050 3150);
DISPLAY INVISIBLE (-1050 3150);
FORCEPROP 1 LAST LOCATION C47
J 0
(-1050 3100);
DISPLAY 0.702128 (-1050 3100);
PAINT YELLOW (-1050 3100);
FORCEPROP 1 LASTPIN (-1100 3100) $PN 1
J 0
(-1090 3080);
DISPLAY 0.808511 (-1090 3080);
PAINT WHITE (-1090 3080);
FORCEPROP 1 LASTPIN (-1100 2900) $PN 2
J 0
(-1090 2880);
DISPLAY 0.808511 (-1090 2880);
PAINT WHITE (-1090 2880);
FORCEPROP 2 LAST $SEC 1
J 0
(-1050 3200);
DISPLAY 0.680851 (-1050 3200);
PAINT MONO (-1050 3200);
DISPLAY INVISIBLE (-1050 3200);
FORCEPROP 0 LAST CDS_SEC 1
J 0
(-1050 3200);
DISPLAY 0.680851 (-1050 3200);
PAINT MONO (-1050 3200);
DISPLAY INVISIBLE (-1050 3200);
FORCEADD OFFPAGE..2
(-450 4050);
FORCEPROP 2 LAST $XR0 16 
J 0
(-261 4050);
DISPLAY 0.638298 (-261 4050);
PAINT MONO (-261 4050);
FORCEPROP 2 LAST CDS_LIB standard
J 0
(-450 4050);
DISPLAY INVISIBLE (-450 4050);
FORCEPROP 1 LAST OFFPAGE TRUE
J 0
(-125 3925);
DISPLAY 0.872340 (-125 3925);
PAINT GREEN (-125 3925);
DISPLAY INVISIBLE (-125 3925);
FORCEPROP 1 LAST COMMENT_BODY TRUE
J 0
(-495 3955);
DISPLAY 0.872340 (-495 3955);
PAINT PEACH (-495 3955);
DISPLAY INVISIBLE (-495 3955);
FORCEPROP 2 LAST PATH I129
J 0
(-275 4125);
DISPLAY 1.021277 (-275 4125);
DISPLAY INVISIBLE (-275 4125);
FORCEADD UNIVERSAL_POWER..1
(225 2300);
FORCEPROP 3 LASTPIN (225 2250) SIG_NAME P3V3_P1V8_I2C_I3C\g
J 0
(235 2260);
DISPLAY 0.659574 (235 2260);
PAINT MONO (235 2260);
DISPLAY INVISIBLE (235 2260);
FORCEPROP 1 LAST HDL_POWER P3V3_P1V8_I2C_I3C
J 1
(225 2350);
DISPLAY 0.702128 (225 2350);
PAINT GREEN (225 2350);
FORCEPROP 2 LAST CDS_LIB logical_power
J 0
(225 2300);
DISPLAY INVISIBLE (225 2300);
FORCEPROP 1 LAST PATH I130
J 0
(275 2325);
DISPLAY 0.872340 (275 2325);
PAINT AQUA (275 2325);
DISPLAY INVISIBLE (275 2325);
FORCEADD Q_RES..1
(-975 2050);
FORCEPROP 1 LAST TOLERANCE 5%
J 0
(-400 2150);
DISPLAY 0.510638 (-400 2150);
PAINT SKYBLUE (-400 2150);
FORCEPROP 1 LAST PACK_TYPE 0402LF
J 0
(-675 2150);
DISPLAY 0.510638 (-675 2150);
PAINT SKYBLUE (-675 2150);
FORCEPROP 1 LAST WATTAGE 1/16W
J 2
(-900 2150);
DISPLAY 0.510638 (-900 2150);
PAINT SKYBLUE (-900 2150);
FORCEPROP 1 LAST VALUE 0
J 2
(-800 2050);
DISPLAY 0.510638 (-800 2050);
PAINT SKYBLUE (-800 2050);
FORCEPROP 1 LAST PART_NUMBER CS00002JB13
J 0
(-1025 2225);
DISPLAY 0.510638 (-1025 2225);
PAINT WHITE (-1025 2225);
FORCEPROP 1 LAST MATERIAL CHIP
J 0
(-875 2150);
DISPLAY 0.510638 (-875 2150);
PAINT SKYBLUE (-875 2150);
FORCEPROP 2 LAST CDS_LIB pure_quanta
J 0
(-975 2050);
DISPLAY INVISIBLE (-975 2050);
FORCEPROP 1 LAST PATH I131
J 0
(-1025 2200);
DISPLAY 0.978723 (-1025 2200);
PAINT WHITE (-1025 2200);
DISPLAY INVISIBLE (-1025 2200);
FORCEPROP 1 LAST LOCATION R231
J 0
(-1250 2050);
DISPLAY 0.702128 (-1250 2050);
PAINT YELLOW (-1250 2050);
FORCEPROP 1 LASTPIN (-1075 2050) $PN 1
J 0
(-1063 2062);
DISPLAY 0.808511 (-1063 2062);
PAINT WHITE (-1063 2062);
FORCEPROP 1 LASTPIN (-875 2050) $PN 2
J 0
(-913 2062);
DISPLAY 0.808511 (-913 2062);
PAINT WHITE (-913 2062);
FORCEPROP 0 LAST $SEC 1
J 0
(-1025 2275);
DISPLAY 0.680851 (-1025 2275);
PAINT MONO (-1025 2275);
DISPLAY INVISIBLE (-1025 2275);
FORCEPROP 0 LAST CDS_SEC 1
J 0
(-1025 2275);
DISPLAY 0.680851 (-1025 2275);
DISPLAY INVISIBLE (-1025 2275);
FORCEADD UNIVERSAL_POWER..1
(-1350 2300);
FORCEPROP 3 LASTPIN (-1350 2250) SIG_NAME P3V3_AUX\g
J 0
(-1340 2260);
DISPLAY 0.659574 (-1340 2260);
PAINT MONO (-1340 2260);
DISPLAY INVISIBLE (-1340 2260);
FORCEPROP 1 LAST HDL_POWER P3V3_AUX
J 1
(-1350 2350);
DISPLAY 0.702128 (-1350 2350);
PAINT GREEN (-1350 2350);
FORCEPROP 2 LAST CDS_LIB logical_power
J 0
(-1350 2300);
DISPLAY INVISIBLE (-1350 2300);
FORCEPROP 1 LAST PATH I132
J 0
(-1300 2325);
DISPLAY 0.872340 (-1300 2325);
PAINT AQUA (-1300 2325);
DISPLAY INVISIBLE (-1300 2325);
FORCEADD Q_CAP..1
(100 1875);
FORCEPROP 1 LAST VOLTAGE 25V
J 0
(150 1875);
DISPLAY 0.510638 (150 1875);
PAINT SKYBLUE (150 1875);
FORCEPROP 1 LAST MATERIAL X7R
J 0
(150 1775);
DISPLAY 0.510638 (150 1775);
PAINT SKYBLUE (150 1775);
FORCEPROP 1 LAST TOLERANCE 10%
J 0
(150 1825);
DISPLAY 0.510638 (150 1825);
PAINT SKYBLUE (150 1825);
FORCEPROP 1 LAST VALUE 0.1UF
J 0
(150 1925);
DISPLAY 0.510638 (150 1925);
PAINT SKYBLUE (150 1925);
FORCEPROP 1 LAST PART_NUMBER CH4104K1B00
J 0
(150 1675);
DISPLAY 0.510638 (150 1675);
PAINT WHITE (150 1675);
FORCEPROP 1 LAST PACK_TYPE 0402
J 0
(150 1725);
DISPLAY 0.510638 (150 1725);
PAINT SKYBLUE (150 1725);
FORCEPROP 2 LAST CDS_LIB pure_quanta
J 0
(100 1875);
DISPLAY INVISIBLE (100 1875);
FORCEPROP 1 LAST PATH I133
J 0
(150 2025);
DISPLAY 0.978723 (150 2025);
PAINT WHITE (150 2025);
DISPLAY INVISIBLE (150 2025);
FORCEPROP 1 LAST LOCATION C57
J 0
(150 1975);
DISPLAY 0.702128 (150 1975);
PAINT YELLOW (150 1975);
FORCEPROP 1 LASTPIN (100 1975) $PN 1
J 0
(110 1955);
DISPLAY 0.808511 (110 1955);
PAINT WHITE (110 1955);
FORCEPROP 1 LASTPIN (100 1775) $PN 2
J 0
(110 1755);
DISPLAY 0.808511 (110 1755);
PAINT WHITE (110 1755);
FORCEPROP 2 LAST $SEC 1
J 0
(150 2075);
DISPLAY 0.680851 (150 2075);
PAINT MONO (150 2075);
DISPLAY INVISIBLE (150 2075);
FORCEPROP 0 LAST CDS_SEC 1
J 0
(150 2075);
DISPLAY 0.680851 (150 2075);
PAINT MONO (150 2075);
DISPLAY INVISIBLE (150 2075);
FORCEADD UNIVERSAL_GND..1
(-75 1575);
FORCEPROP 3 LASTPIN (-75 1625) SIG_NAME GND\g
J 0
(-65 1635);
DISPLAY 0.659574 (-65 1635);
PAINT MONO (-65 1635);
DISPLAY INVISIBLE (-65 1635);
FORCEPROP 2 LAST CDS_LIB logical_power
J 0
(-75 1575);
DISPLAY INVISIBLE (-75 1575);
FORCEPROP 1 LAST HDL_POWER GND
J 1
(-50 1500);
DISPLAY 0.702128 (-50 1500);
PAINT GREEN (-50 1500);
DISPLAY INVISIBLE (-50 1500);
FORCEPROP 1 LAST PATH I134
J 0
(0 1575);
DISPLAY 0.872340 (0 1575);
PAINT AQUA (0 1575);
DISPLAY INVISIBLE (0 1575);
FORCEADD Q_CAP..1
(-250 1875);
FORCEPROP 1 LAST MATERIAL X6S
J 0
(-200 1775);
DISPLAY 0.510638 (-200 1775);
PAINT SKYBLUE (-200 1775);
FORCEPROP 1 LAST PART_NUMBER CH5104KEB02
J 0
(-200 1675);
DISPLAY 0.510638 (-200 1675);
PAINT WHITE (-200 1675);
FORCEPROP 1 LAST VOLTAGE 25V
J 0
(-200 1875);
DISPLAY 0.510638 (-200 1875);
PAINT SKYBLUE (-200 1875);
FORCEPROP 1 LAST VALUE 1UF
J 0
(-200 1925);
DISPLAY 0.510638 (-200 1925);
PAINT SKYBLUE (-200 1925);
FORCEPROP 1 LAST TOLERANCE 10%
J 0
(-200 1825);
DISPLAY 0.510638 (-200 1825);
PAINT SKYBLUE (-200 1825);
FORCEPROP 1 LAST PACK_TYPE C0402
J 0
(-200 1725);
DISPLAY 0.510638 (-200 1725);
PAINT SKYBLUE (-200 1725);
FORCEPROP 2 LAST CDS_LIB pure_quanta
J 0
(-250 1875);
DISPLAY INVISIBLE (-250 1875);
FORCEPROP 1 LAST PATH I135
J 0
(-200 2025);
DISPLAY 0.978723 (-200 2025);
PAINT WHITE (-200 2025);
DISPLAY INVISIBLE (-200 2025);
FORCEPROP 1 LAST LOCATION C53
J 0
(-200 1975);
DISPLAY 0.702128 (-200 1975);
PAINT YELLOW (-200 1975);
FORCEPROP 1 LASTPIN (-250 1975) $PN 1
J 0
(-240 1955);
DISPLAY 0.808511 (-240 1955);
PAINT WHITE (-240 1955);
FORCEPROP 1 LASTPIN (-250 1775) $PN 2
J 0
(-240 1755);
DISPLAY 0.808511 (-240 1755);
PAINT WHITE (-240 1755);
FORCEPROP 2 LAST $SEC 1
J 0
(-200 2075);
DISPLAY 0.680851 (-200 2075);
PAINT MONO (-200 2075);
DISPLAY INVISIBLE (-200 2075);
FORCEPROP 0 LAST CDS_SEC 1
J 0
(-200 2075);
DISPLAY 0.680851 (-200 2075);
PAINT MONO (-200 2075);
DISPLAY INVISIBLE (-200 2075);
FORCEADD Q_RES..1
(-875 1775);
FORCEPROP 1 LAST VALUE 0
J 2
(-675 1775);
DISPLAY 0.510638 (-675 1775);
PAINT SKYBLUE (-675 1775);
FORCEPROP 1 LAST MATERIAL EMPTY
J 0
(-600 1775);
DISPLAY 0.510638 (-600 1775);
PAINT RED (-600 1775);
FORCEPROP 1 LAST PACK_TYPE 0402LF
J 0
(-750 1650);
DISPLAY 0.510638 (-750 1650);
PAINT SKYBLUE (-750 1650);
FORCEPROP 1 LAST PART_NUMBER CS00002JB13
J 0
(-750 1700);
DISPLAY 0.510638 (-750 1700);
PAINT WHITE (-750 1700);
FORCEPROP 1 LAST TOLERANCE 5%
J 0
(-300 1650);
DISPLAY 0.510638 (-300 1650);
PAINT SKYBLUE (-300 1650);
FORCEPROP 1 LAST WATTAGE 1/16W
J 2
(-325 1650);
DISPLAY 0.510638 (-325 1650);
PAINT SKYBLUE (-325 1650);
FORCEPROP 2 LAST CDS_LIB pure_quanta
J 0
(-875 1775);
DISPLAY INVISIBLE (-875 1775);
FORCEPROP 1 LAST PATH I136
J 0
(-925 1925);
DISPLAY 0.978723 (-925 1925);
PAINT WHITE (-925 1925);
DISPLAY INVISIBLE (-925 1925);
FORCEPROP 1 LAST LOCATION R232
J 0
(-1200 1775);
DISPLAY 0.702128 (-1200 1775);
PAINT YELLOW (-1200 1775);
FORCEPROP 1 LASTPIN (-975 1775) $PN 1
J 0
(-963 1787);
DISPLAY 0.808511 (-963 1787);
PAINT WHITE (-963 1787);
FORCEPROP 1 LASTPIN (-775 1775) $PN 2
J 0
(-813 1787);
DISPLAY 0.808511 (-813 1787);
PAINT WHITE (-813 1787);
FORCEPROP 0 LAST $SEC 1
J 0
(-600 1825);
DISPLAY 0.680851 (-600 1825);
PAINT MONO (-600 1825);
DISPLAY INVISIBLE (-600 1825);
FORCEPROP 0 LAST CDS_SEC 1
J 0
(-600 1825);
DISPLAY 0.680851 (-600 1825);
DISPLAY INVISIBLE (-600 1825);
FORCEADD UNIVERSAL_POWER..1
(-1450 1925);
FORCEPROP 3 LASTPIN (-1450 1875) SIG_NAME P1V8_AUX\g
J 0
(-1440 1885);
DISPLAY 0.659574 (-1440 1885);
PAINT MONO (-1440 1885);
DISPLAY INVISIBLE (-1440 1885);
FORCEPROP 1 LAST HDL_POWER P1V8_AUX
J 1
(-1450 1975);
DISPLAY 0.702128 (-1450 1975);
PAINT GREEN (-1450 1975);
FORCEPROP 2 LAST CDS_LIB logical_power
J 0
(-1450 1925);
DISPLAY INVISIBLE (-1450 1925);
FORCEPROP 1 LAST PATH I137
J 0
(-1400 1950);
DISPLAY 0.872340 (-1400 1950);
PAINT AQUA (-1400 1950);
DISPLAY INVISIBLE (-1400 1950);
FORCEADD OFFPAGE..2
(825 1050);
FORCEPROP 2 LAST $XR0 16 
J 0
(1014 1050);
DISPLAY 0.638298 (1014 1050);
PAINT MONO (1014 1050);
FORCEPROP 2 LAST CDS_LIB standard
J 0
(825 1050);
DISPLAY INVISIBLE (825 1050);
FORCEPROP 1 LAST OFFPAGE TRUE
J 0
(1150 925);
DISPLAY 0.872340 (1150 925);
PAINT GREEN (1150 925);
DISPLAY INVISIBLE (1150 925);
FORCEPROP 1 LAST COMMENT_BODY TRUE
J 0
(780 955);
DISPLAY 0.872340 (780 955);
PAINT PEACH (780 955);
DISPLAY INVISIBLE (780 955);
FORCEPROP 2 LAST PATH I138
J 0
(1025 1100);
DISPLAY 1.021277 (1025 1100);
DISPLAY INVISIBLE (1025 1100);
FORCEADD Q_CAP..1
(425 875);
FORCEPROP 1 LAST PART_NUMBER CH4104K1B00
J 0
(475 675);
DISPLAY 0.510638 (475 675);
PAINT WHITE (475 675);
FORCEPROP 1 LAST VOLTAGE 25V
J 0
(475 875);
DISPLAY 0.510638 (475 875);
PAINT SKYBLUE (475 875);
FORCEPROP 1 LAST MATERIAL X7R
J 0
(475 775);
DISPLAY 0.510638 (475 775);
PAINT SKYBLUE (475 775);
FORCEPROP 1 LAST TOLERANCE 10%
J 0
(475 825);
DISPLAY 0.510638 (475 825);
PAINT SKYBLUE (475 825);
FORCEPROP 1 LAST VALUE 0.1UF
J 0
(475 925);
DISPLAY 0.510638 (475 925);
PAINT SKYBLUE (475 925);
FORCEPROP 1 LAST PACK_TYPE 0402
J 0
(475 725);
DISPLAY 0.510638 (475 725);
PAINT SKYBLUE (475 725);
FORCEPROP 2 LAST CDS_LIB pure_quanta
J 0
(425 875);
DISPLAY INVISIBLE (425 875);
FORCEPROP 1 LAST PATH I139
J 0
(475 1025);
DISPLAY 0.978723 (475 1025);
PAINT WHITE (475 1025);
DISPLAY INVISIBLE (475 1025);
FORCEPROP 1 LAST LOCATION C65
J 0
(475 975);
DISPLAY 0.702128 (475 975);
PAINT YELLOW (475 975);
FORCEPROP 1 LASTPIN (425 975) $PN 1
J 0
(435 955);
DISPLAY 0.808511 (435 955);
PAINT WHITE (435 955);
FORCEPROP 1 LASTPIN (425 775) $PN 2
J 0
(435 755);
DISPLAY 0.808511 (435 755);
PAINT WHITE (435 755);
FORCEPROP 2 LAST $SEC 1
J 0
(475 1075);
DISPLAY 0.680851 (475 1075);
PAINT MONO (475 1075);
DISPLAY INVISIBLE (475 1075);
FORCEPROP 0 LAST CDS_SEC 1
J 0
(475 1075);
DISPLAY 0.680851 (475 1075);
PAINT MONO (475 1075);
DISPLAY INVISIBLE (475 1075);
FORCEADD UNIVERSAL_GND..1
(300 600);
FORCEPROP 3 LASTPIN (300 650) SIG_NAME GND\g
J 0
(310 660);
DISPLAY 0.659574 (310 660);
PAINT MONO (310 660);
DISPLAY INVISIBLE (310 660);
FORCEPROP 2 LAST CDS_LIB logical_power
J 0
(300 600);
DISPLAY INVISIBLE (300 600);
FORCEPROP 1 LAST HDL_POWER GND
J 1
(325 525);
DISPLAY 0.702128 (325 525);
PAINT GREEN (325 525);
DISPLAY INVISIBLE (325 525);
FORCEPROP 1 LAST PATH I140
J 0
(375 600);
DISPLAY 0.872340 (375 600);
PAINT AQUA (375 600);
DISPLAY INVISIBLE (375 600);
FORCEADD Q_CAP..1
(225 875);
FORCEPROP 1 LAST MATERIAL X6S
J 0
(275 775);
DISPLAY 0.510638 (275 775);
PAINT SKYBLUE (275 775);
FORCEPROP 1 LAST TOLERANCE 10%
J 0
(275 825);
DISPLAY 0.510638 (275 825);
PAINT SKYBLUE (275 825);
FORCEPROP 1 LAST PACK_TYPE C0402
J 0
(250 725);
DISPLAY 0.510638 (250 725);
PAINT SKYBLUE (250 725);
FORCEPROP 1 LAST VOLTAGE 25V
J 0
(275 875);
DISPLAY 0.510638 (275 875);
PAINT SKYBLUE (275 875);
FORCEPROP 1 LAST VALUE 1UF
J 0
(275 925);
DISPLAY 0.510638 (275 925);
PAINT SKYBLUE (275 925);
FORCEPROP 1 LAST PART_NUMBER CH5104KEB02
R 3
J 0
(150 1025);
DISPLAY 0.510638 (150 1025);
PAINT WHITE (150 1025);
FORCEPROP 2 LAST CDS_LIB pure_quanta
J 0
(225 875);
DISPLAY INVISIBLE (225 875);
FORCEPROP 1 LAST PATH I141
J 0
(275 1025);
DISPLAY 0.978723 (275 1025);
PAINT WHITE (275 1025);
DISPLAY INVISIBLE (275 1025);
FORCEPROP 1 LAST LOCATION C60
J 0
(275 975);
DISPLAY 0.702128 (275 975);
PAINT YELLOW (275 975);
FORCEPROP 1 LASTPIN (225 975) $PN 1
J 0
(235 955);
DISPLAY 0.808511 (235 955);
PAINT WHITE (235 955);
FORCEPROP 1 LASTPIN (225 775) $PN 2
J 0
(235 755);
DISPLAY 0.808511 (235 755);
PAINT WHITE (235 755);
FORCEPROP 2 LAST $SEC 1
J 0
(275 1075);
DISPLAY 0.680851 (275 1075);
PAINT MONO (275 1075);
DISPLAY INVISIBLE (275 1075);
FORCEPROP 0 LAST CDS_SEC 1
J 0
(275 1075);
DISPLAY 0.680851 (275 1075);
PAINT MONO (275 1075);
DISPLAY INVISIBLE (275 1075);
FORCEADD Q_INDUCTOR..1
(-125 1075);
FORCEPROP 2 LAST PACK_TYPE SMLF
J 0
(-250 1275);
DISPLAY 0.510638 (-250 1275);
PAINT SKYBLUE (-250 1275);
FORCEPROP 2 LAST VALUE BLM18PG121SN1D/2000MA
J 0
(-250 1325);
DISPLAY 0.510638 (-250 1325);
PAINT SKYBLUE (-250 1325);
FORCEPROP 1 LAST MATERIAL EMPTY
J 0
(-50 1125);
DISPLAY 0.510638 (-50 1125);
PAINT RED (-50 1125);
FORCEPROP 1 LAST PART_NUMBER CX8PG121009
J 0
(-250 1185);
DISPLAY 0.510638 (-250 1185);
PAINT WHITE (-250 1185);
FORCEPROP 1 LAST PATH I142
J 0
(-50 1130);
DISPLAY 0.723404 (-50 1130);
PAINT GREEN (-50 1130);
DISPLAY INVISIBLE (-50 1130);
FORCEPROP 1 LAST NEEDS_NO_SIZE TRUE
J 0
(-125 1075);
DISPLAY 0.468085 (-125 1075);
PAINT GREEN (-125 1075);
DISPLAY INVISIBLE (-125 1075);
FORCEPROP 2 LAST CDS_LIB pure_quanta
J 0
(-125 1075);
DISPLAY INVISIBLE (-125 1075);
FORCEPROP 1 LAST LOCATION L9
J 0
(-250 1235);
DISPLAY 0.702128 (-250 1235);
PAINT YELLOW (-250 1235);
FORCEPROP 2 LASTPIN (-225 1050) $PN 1
J 2
(-235 1060);
DISPLAY 0.808511 (-235 1060);
PAINT WHITE (-235 1060);
FORCEPROP 2 LASTPIN (-25 1050) $PN 2
J 0
(-15 1060);
DISPLAY 0.808511 (-15 1060);
PAINT WHITE (-15 1060);
FORCEPROP 2 LAST $SEC 1
J 0
(-250 1375);
DISPLAY 0.680851 (-250 1375);
PAINT MONO (-250 1375);
DISPLAY INVISIBLE (-250 1375);
FORCEPROP 0 LAST CDS_SEC 1
J 0
(-250 1375);
DISPLAY 0.680851 (-250 1375);
PAINT MONO (-250 1375);
DISPLAY INVISIBLE (-250 1375);
FORCEADD UNIVERSAL_POWER..1
(-475 1250);
FORCEPROP 3 LASTPIN (-475 1200) SIG_NAME P3V3_AUX\g
J 0
(-465 1210);
DISPLAY 0.659574 (-465 1210);
PAINT MONO (-465 1210);
DISPLAY INVISIBLE (-465 1210);
FORCEPROP 1 LAST HDL_POWER P3V3_AUX
J 1
(-475 1300);
DISPLAY 0.702128 (-475 1300);
PAINT GREEN (-475 1300);
FORCEPROP 2 LAST CDS_LIB logical_power
J 0
(-475 1250);
DISPLAY INVISIBLE (-475 1250);
FORCEPROP 1 LAST PATH I143
J 0
(-425 1275);
DISPLAY 0.872340 (-425 1275);
PAINT AQUA (-425 1275);
DISPLAY INVISIBLE (-425 1275);
FORCEADD OFFPAGE..2
(-525 925);
FORCEPROP 2 LAST $XR0 16 
J 0
(-336 925);
DISPLAY 0.638298 (-336 925);
PAINT MONO (-336 925);
FORCEPROP 2 LAST CDS_LIB standard
J 0
(-525 925);
DISPLAY INVISIBLE (-525 925);
FORCEPROP 1 LAST OFFPAGE TRUE
J 0
(-200 800);
DISPLAY 0.872340 (-200 800);
PAINT GREEN (-200 800);
DISPLAY INVISIBLE (-200 800);
FORCEPROP 1 LAST COMMENT_BODY TRUE
J 0
(-570 830);
DISPLAY 0.872340 (-570 830);
PAINT PEACH (-570 830);
DISPLAY INVISIBLE (-570 830);
FORCEPROP 2 LAST PATH I144
J 0
(-325 975);
DISPLAY 1.021277 (-325 975);
DISPLAY INVISIBLE (-325 975);
FORCEADD Q_CAP..1
(-900 750);
FORCEPROP 1 LAST VOLTAGE 25V
J 0
(-850 750);
DISPLAY 0.510638 (-850 750);
PAINT SKYBLUE (-850 750);
FORCEPROP 1 LAST TOLERANCE 10%
J 0
(-850 700);
DISPLAY 0.510638 (-850 700);
PAINT SKYBLUE (-850 700);
FORCEPROP 1 LAST PACK_TYPE 0402
J 0
(-850 600);
DISPLAY 0.510638 (-850 600);
PAINT SKYBLUE (-850 600);
FORCEPROP 1 LAST MATERIAL X7R
J 0
(-850 650);
DISPLAY 0.510638 (-850 650);
PAINT SKYBLUE (-850 650);
FORCEPROP 1 LAST PART_NUMBER CH4104K1B00
J 0
(-850 550);
DISPLAY 0.510638 (-850 550);
PAINT WHITE (-850 550);
FORCEPROP 1 LAST VALUE 0.1UF
J 0
(-850 800);
DISPLAY 0.510638 (-850 800);
PAINT SKYBLUE (-850 800);
FORCEPROP 2 LAST CDS_LIB pure_quanta
J 0
(-900 750);
DISPLAY INVISIBLE (-900 750);
FORCEPROP 1 LAST PATH I145
J 0
(-850 900);
DISPLAY 0.978723 (-850 900);
PAINT WHITE (-850 900);
DISPLAY INVISIBLE (-850 900);
FORCEPROP 1 LAST LOCATION C51
J 0
(-850 850);
DISPLAY 0.702128 (-850 850);
PAINT YELLOW (-850 850);
FORCEPROP 1 LASTPIN (-900 850) $PN 1
J 0
(-890 830);
DISPLAY 0.808511 (-890 830);
PAINT WHITE (-890 830);
FORCEPROP 1 LASTPIN (-900 650) $PN 2
J 0
(-890 630);
DISPLAY 0.808511 (-890 630);
PAINT WHITE (-890 630);
FORCEPROP 2 LAST $SEC 1
J 0
(-850 950);
DISPLAY 0.680851 (-850 950);
PAINT MONO (-850 950);
DISPLAY INVISIBLE (-850 950);
FORCEPROP 0 LAST CDS_SEC 1
J 0
(-850 950);
DISPLAY 0.680851 (-850 950);
PAINT MONO (-850 950);
DISPLAY INVISIBLE (-850 950);
FORCEADD Q_INDUCTOR..1
(-1400 950);
FORCEPROP 2 LAST PACK_TYPE SMLF
J 0
(-1525 1150);
DISPLAY 0.510638 (-1525 1150);
PAINT SKYBLUE (-1525 1150);
FORCEPROP 1 LAST PART_NUMBER CX8PG121009
J 0
(-1525 1060);
DISPLAY 0.510638 (-1525 1060);
PAINT WHITE (-1525 1060);
FORCEPROP 1 LAST MATERIAL IND
J 0
(-1525 1005);
DISPLAY 0.510638 (-1525 1005);
PAINT SKYBLUE (-1525 1005);
FORCEPROP 2 LAST VALUE BLM18PG121SN1D/2000MA
J 0
(-1525 1200);
DISPLAY 0.510638 (-1525 1200);
PAINT SKYBLUE (-1525 1200);
FORCEPROP 2 LAST CDS_LIB pure_quanta
J 0
(-1400 950);
DISPLAY INVISIBLE (-1400 950);
FORCEPROP 1 LAST NEEDS_NO_SIZE TRUE
J 0
(-1400 950);
DISPLAY 0.468085 (-1400 950);
PAINT GREEN (-1400 950);
DISPLAY INVISIBLE (-1400 950);
FORCEPROP 1 LAST PATH I146
J 0
(-1325 1005);
DISPLAY 0.723404 (-1325 1005);
PAINT GREEN (-1325 1005);
DISPLAY INVISIBLE (-1325 1005);
FORCEPROP 1 LAST LOCATION L7
J 0
(-1525 1110);
DISPLAY 0.702128 (-1525 1110);
PAINT YELLOW (-1525 1110);
FORCEPROP 2 LASTPIN (-1500 925) $PN 1
J 2
(-1510 935);
DISPLAY 0.808511 (-1510 935);
PAINT WHITE (-1510 935);
FORCEPROP 2 LASTPIN (-1300 925) $PN 2
J 0
(-1290 935);
DISPLAY 0.808511 (-1290 935);
PAINT WHITE (-1290 935);
FORCEPROP 2 LAST $SEC 1
J 0
(-1525 1250);
DISPLAY 0.680851 (-1525 1250);
PAINT MONO (-1525 1250);
DISPLAY INVISIBLE (-1525 1250);
FORCEPROP 0 LAST CDS_SEC 1
J 0
(-1525 1250);
DISPLAY 0.680851 (-1525 1250);
PAINT MONO (-1525 1250);
DISPLAY INVISIBLE (-1525 1250);
FORCEADD UNIVERSAL_POWER..1
(-1700 1000);
FORCEPROP 3 LASTPIN (-1700 950) SIG_NAME P3V3_AUX\g
J 0
(-1690 960);
DISPLAY 0.659574 (-1690 960);
PAINT MONO (-1690 960);
DISPLAY INVISIBLE (-1690 960);
FORCEPROP 1 LAST HDL_POWER P3V3_AUX
J 1
(-1700 1050);
DISPLAY 0.702128 (-1700 1050);
PAINT GREEN (-1700 1050);
FORCEPROP 2 LAST CDS_LIB logical_power
J 0
(-1700 1000);
DISPLAY INVISIBLE (-1700 1000);
FORCEPROP 1 LAST PATH I147
J 0
(-1650 1025);
DISPLAY 0.872340 (-1650 1025);
PAINT AQUA (-1650 1025);
DISPLAY INVISIBLE (-1650 1025);
FORCEADD Q_CAP..1
(-1100 750);
FORCEPROP 1 LAST TOLERANCE 10%
J 0
(-1050 700);
DISPLAY 0.510638 (-1050 700);
PAINT SKYBLUE (-1050 700);
FORCEPROP 1 LAST PART_NUMBER CH5104KEB02
R 3
J 0
(-1200 875);
DISPLAY 0.510638 (-1200 875);
PAINT WHITE (-1200 875);
FORCEPROP 1 LAST VALUE 1UF
J 0
(-1050 800);
DISPLAY 0.510638 (-1050 800);
PAINT SKYBLUE (-1050 800);
FORCEPROP 1 LAST PACK_TYPE C0402
J 0
(-1075 600);
DISPLAY 0.510638 (-1075 600);
PAINT SKYBLUE (-1075 600);
FORCEPROP 1 LAST MATERIAL X6S
J 0
(-1050 650);
DISPLAY 0.510638 (-1050 650);
PAINT SKYBLUE (-1050 650);
FORCEPROP 1 LAST VOLTAGE 25V
J 0
(-1050 750);
DISPLAY 0.510638 (-1050 750);
PAINT SKYBLUE (-1050 750);
FORCEPROP 2 LAST CDS_LIB pure_quanta
J 0
(-1100 750);
DISPLAY INVISIBLE (-1100 750);
FORCEPROP 1 LAST PATH I148
J 0
(-1050 900);
DISPLAY 0.978723 (-1050 900);
PAINT WHITE (-1050 900);
DISPLAY INVISIBLE (-1050 900);
FORCEPROP 1 LAST LOCATION C48
J 0
(-1050 850);
DISPLAY 0.702128 (-1050 850);
PAINT YELLOW (-1050 850);
FORCEPROP 1 LASTPIN (-1100 850) $PN 1
J 0
(-1090 830);
DISPLAY 0.808511 (-1090 830);
PAINT WHITE (-1090 830);
FORCEPROP 1 LASTPIN (-1100 650) $PN 2
J 0
(-1090 630);
DISPLAY 0.808511 (-1090 630);
PAINT WHITE (-1090 630);
FORCEPROP 2 LAST $SEC 1
J 0
(-1050 950);
DISPLAY 0.680851 (-1050 950);
PAINT MONO (-1050 950);
DISPLAY INVISIBLE (-1050 950);
FORCEPROP 0 LAST CDS_SEC 1
J 0
(-1050 950);
DISPLAY 0.680851 (-1050 950);
PAINT MONO (-1050 950);
DISPLAY INVISIBLE (-1050 950);
FORCEADD UNIVERSAL_GND..1
(-1000 475);
FORCEPROP 3 LASTPIN (-1000 525) SIG_NAME GND\g
J 0
(-990 535);
DISPLAY 0.659574 (-990 535);
PAINT MONO (-990 535);
DISPLAY INVISIBLE (-990 535);
FORCEPROP 2 LAST CDS_LIB logical_power
J 0
(-1000 475);
DISPLAY INVISIBLE (-1000 475);
FORCEPROP 1 LAST HDL_POWER GND
J 1
(-975 400);
DISPLAY 0.702128 (-975 400);
PAINT GREEN (-975 400);
DISPLAY INVISIBLE (-975 400);
FORCEPROP 1 LAST PATH I149
J 0
(-925 475);
DISPLAY 0.872340 (-925 475);
PAINT AQUA (-925 475);
DISPLAY INVISIBLE (-925 475);
FORCEADD OFFPAGE..2
(800 -75);
FORCEPROP 2 LAST $XR0 16 
J 0
(989 -75);
DISPLAY 0.638298 (989 -75);
PAINT MONO (989 -75);
FORCEPROP 2 LAST CDS_LIB standard
J 0
(800 -75);
DISPLAY INVISIBLE (800 -75);
FORCEPROP 1 LAST OFFPAGE TRUE
J 0
(1125 -200);
DISPLAY 0.872340 (1125 -200);
PAINT GREEN (1125 -200);
DISPLAY INVISIBLE (1125 -200);
FORCEPROP 1 LAST COMMENT_BODY TRUE
J 0
(755 -170);
DISPLAY 0.872340 (755 -170);
PAINT PEACH (755 -170);
DISPLAY INVISIBLE (755 -170);
FORCEPROP 2 LAST PATH I150
J 0
(1125 -25);
DISPLAY 1.021277 (1125 -25);
DISPLAY INVISIBLE (1125 -25);
FORCEADD Q_CAP..1
(350 -250);
FORCEPROP 1 LAST PART_NUMBER CH4104K1B00
J 0
(400 -450);
DISPLAY 0.510638 (400 -450);
PAINT WHITE (400 -450);
FORCEPROP 1 LAST VOLTAGE 25V
J 0
(400 -250);
DISPLAY 0.510638 (400 -250);
PAINT SKYBLUE (400 -250);
FORCEPROP 1 LAST MATERIAL X7R
J 0
(400 -350);
DISPLAY 0.510638 (400 -350);
PAINT SKYBLUE (400 -350);
FORCEPROP 1 LAST TOLERANCE 10%
J 0
(400 -300);
DISPLAY 0.510638 (400 -300);
PAINT SKYBLUE (400 -300);
FORCEPROP 1 LAST VALUE 0.1UF
J 0
(400 -200);
DISPLAY 0.510638 (400 -200);
PAINT SKYBLUE (400 -200);
FORCEPROP 1 LAST PACK_TYPE 0402
J 0
(400 -400);
DISPLAY 0.510638 (400 -400);
PAINT SKYBLUE (400 -400);
FORCEPROP 2 LAST CDS_LIB pure_quanta
J 0
(350 -250);
DISPLAY INVISIBLE (350 -250);
FORCEPROP 1 LAST PATH I151
J 0
(400 -100);
DISPLAY 0.978723 (400 -100);
PAINT WHITE (400 -100);
DISPLAY INVISIBLE (400 -100);
FORCEPROP 1 LAST LOCATION C81
J 0
(400 -150);
DISPLAY 0.702128 (400 -150);
PAINT YELLOW (400 -150);
FORCEPROP 1 LASTPIN (350 -150) $PN 1
J 0
(360 -170);
DISPLAY 0.808511 (360 -170);
PAINT WHITE (360 -170);
FORCEPROP 1 LASTPIN (350 -350) $PN 2
J 0
(360 -370);
DISPLAY 0.808511 (360 -370);
PAINT WHITE (360 -370);
FORCEPROP 2 LAST $SEC 1
J 0
(400 -50);
DISPLAY 0.680851 (400 -50);
PAINT MONO (400 -50);
DISPLAY INVISIBLE (400 -50);
FORCEPROP 0 LAST CDS_SEC 1
J 0
(400 -50);
DISPLAY 0.680851 (400 -50);
PAINT MONO (400 -50);
DISPLAY INVISIBLE (400 -50);
FORCEADD UNIVERSAL_GND..1
(250 -525);
FORCEPROP 3 LASTPIN (250 -475) SIG_NAME GND\g
J 0
(260 -465);
DISPLAY 0.659574 (260 -465);
PAINT MONO (260 -465);
DISPLAY INVISIBLE (260 -465);
FORCEPROP 2 LAST CDS_LIB logical_power
J 0
(250 -525);
DISPLAY INVISIBLE (250 -525);
FORCEPROP 1 LAST HDL_POWER GND
J 1
(275 -600);
DISPLAY 0.702128 (275 -600);
PAINT GREEN (275 -600);
DISPLAY INVISIBLE (275 -600);
FORCEPROP 1 LAST PATH I152
J 0
(325 -525);
DISPLAY 0.872340 (325 -525);
PAINT AQUA (325 -525);
DISPLAY INVISIBLE (325 -525);
FORCEADD Q_CAP..1
(150 -250);
FORCEPROP 1 LAST PART_NUMBER CH5104KEB02
R 3
J 0
(50 -100);
DISPLAY 0.510638 (50 -100);
PAINT WHITE (50 -100);
FORCEPROP 1 LAST VALUE 1UF
J 0
(200 -200);
DISPLAY 0.510638 (200 -200);
PAINT SKYBLUE (200 -200);
FORCEPROP 1 LAST VOLTAGE 25V
J 0
(200 -250);
DISPLAY 0.510638 (200 -250);
PAINT SKYBLUE (200 -250);
FORCEPROP 1 LAST MATERIAL X6S
J 0
(200 -350);
DISPLAY 0.510638 (200 -350);
PAINT SKYBLUE (200 -350);
FORCEPROP 1 LAST TOLERANCE 10%
J 0
(200 -300);
DISPLAY 0.510638 (200 -300);
PAINT SKYBLUE (200 -300);
FORCEPROP 1 LAST PACK_TYPE C0402
J 0
(175 -400);
DISPLAY 0.510638 (175 -400);
PAINT SKYBLUE (175 -400);
FORCEPROP 2 LAST CDS_LIB pure_quanta
J 0
(150 -250);
DISPLAY INVISIBLE (150 -250);
FORCEPROP 1 LAST PATH I153
J 0
(200 -100);
DISPLAY 0.978723 (200 -100);
PAINT WHITE (200 -100);
DISPLAY INVISIBLE (200 -100);
FORCEPROP 1 LAST LOCATION C80
J 0
(200 -150);
DISPLAY 0.702128 (200 -150);
PAINT YELLOW (200 -150);
FORCEPROP 1 LASTPIN (150 -150) $PN 1
J 0
(160 -170);
DISPLAY 0.808511 (160 -170);
PAINT WHITE (160 -170);
FORCEPROP 1 LASTPIN (150 -350) $PN 2
J 0
(160 -370);
DISPLAY 0.808511 (160 -370);
PAINT WHITE (160 -370);
FORCEPROP 2 LAST $SEC 1
J 0
(200 -50);
DISPLAY 0.680851 (200 -50);
PAINT MONO (200 -50);
DISPLAY INVISIBLE (200 -50);
FORCEPROP 0 LAST CDS_SEC 1
J 0
(200 -50);
DISPLAY 0.680851 (200 -50);
PAINT MONO (200 -50);
DISPLAY INVISIBLE (200 -50);
FORCEADD Q_INDUCTOR..1
(-150 -50);
FORCEPROP 2 LASTPIN (-50 -75) SIG_NAME P1V8_STBY_RC_VCC18A
J 0
(15 -65);
DISPLAY 0.808511 (15 -65);
FORCEPROP 1 LAST MATERIAL IND
J 0
(-275 5);
DISPLAY 0.510638 (-275 5);
PAINT SKYBLUE (-275 5);
FORCEPROP 1 LAST PART_NUMBER CX8PG121009
J 0
(-275 60);
DISPLAY 0.510638 (-275 60);
PAINT WHITE (-275 60);
FORCEPROP 2 LAST PACK_TYPE SMLF
J 0
(-275 150);
DISPLAY 0.510638 (-275 150);
PAINT SKYBLUE (-275 150);
FORCEPROP 2 LAST VALUE BLM18PG121SN1D/2000MA
J 0
(-275 200);
DISPLAY 0.510638 (-275 200);
PAINT SKYBLUE (-275 200);
FORCEPROP 2 LAST CDS_LIB pure_quanta
J 0
(-150 -50);
DISPLAY INVISIBLE (-150 -50);
FORCEPROP 1 LAST NEEDS_NO_SIZE TRUE
J 0
(-150 -50);
DISPLAY 0.468085 (-150 -50);
PAINT GREEN (-150 -50);
DISPLAY INVISIBLE (-150 -50);
FORCEPROP 1 LAST PATH I154
J 0
(-75 5);
DISPLAY 0.723404 (-75 5);
PAINT GREEN (-75 5);
DISPLAY INVISIBLE (-75 5);
FORCEPROP 1 LAST LOCATION L14
J 0
(-275 110);
DISPLAY 0.702128 (-275 110);
PAINT YELLOW (-275 110);
FORCEPROP 2 LASTPIN (-250 -75) $PN 1
J 2
(-260 -65);
DISPLAY 0.808511 (-260 -65);
PAINT WHITE (-260 -65);
FORCEPROP 2 LASTPIN (-50 -75) $PN 2
J 0
(-40 -65);
DISPLAY 0.808511 (-40 -65);
PAINT WHITE (-40 -65);
FORCEPROP 2 LAST $SEC 1
J 0
(-275 250);
DISPLAY 0.680851 (-275 250);
PAINT MONO (-275 250);
DISPLAY INVISIBLE (-275 250);
FORCEPROP 0 LAST CDS_SEC 1
J 0
(-275 250);
DISPLAY 0.680851 (-275 250);
PAINT MONO (-275 250);
DISPLAY INVISIBLE (-275 250);
FORCEADD UNIVERSAL_POWER..1
(-450 0);
FORCEPROP 3 LASTPIN (-450 -50) SIG_NAME P1V8_AUX\g
J 0
(-440 -40);
DISPLAY 0.659574 (-440 -40);
PAINT MONO (-440 -40);
DISPLAY INVISIBLE (-440 -40);
FORCEPROP 1 LAST HDL_POWER P1V8_AUX
J 1
(-450 50);
DISPLAY 0.702128 (-450 50);
PAINT GREEN (-450 50);
FORCEPROP 2 LAST CDS_LIB logical_power
J 0
(-450 0);
DISPLAY INVISIBLE (-450 0);
FORCEPROP 1 LAST PATH I155
J 0
(-400 25);
DISPLAY 0.872340 (-400 25);
PAINT AQUA (-400 25);
DISPLAY INVISIBLE (-400 25);
FORCEADD OFFPAGE..2
(-550 -125);
FORCEPROP 2 LAST $XR0 16 
J 0
(-361 -125);
DISPLAY 0.638298 (-361 -125);
PAINT MONO (-361 -125);
FORCEPROP 2 LAST CDS_LIB standard
J 0
(-550 -125);
DISPLAY INVISIBLE (-550 -125);
FORCEPROP 1 LAST OFFPAGE TRUE
J 0
(-225 -250);
DISPLAY 0.872340 (-225 -250);
PAINT GREEN (-225 -250);
DISPLAY INVISIBLE (-225 -250);
FORCEPROP 1 LAST COMMENT_BODY TRUE
J 0
(-595 -220);
DISPLAY 0.872340 (-595 -220);
PAINT PEACH (-595 -220);
DISPLAY INVISIBLE (-595 -220);
FORCEPROP 2 LAST PATH I156
J 0
(-350 -75);
DISPLAY 1.021277 (-350 -75);
DISPLAY INVISIBLE (-350 -75);
FORCEADD Q_CAP..1
(-975 -300);
FORCEPROP 1 LAST VALUE 0.1UF
J 0
(-925 -250);
DISPLAY 0.510638 (-925 -250);
PAINT SKYBLUE (-925 -250);
FORCEPROP 1 LAST PART_NUMBER CH4104K1B00
J 0
(-925 -500);
DISPLAY 0.510638 (-925 -500);
PAINT WHITE (-925 -500);
FORCEPROP 1 LAST VOLTAGE 25V
J 0
(-925 -300);
DISPLAY 0.510638 (-925 -300);
PAINT SKYBLUE (-925 -300);
FORCEPROP 1 LAST MATERIAL X7R
J 0
(-925 -400);
DISPLAY 0.510638 (-925 -400);
PAINT SKYBLUE (-925 -400);
FORCEPROP 1 LAST TOLERANCE 10%
J 0
(-925 -350);
DISPLAY 0.510638 (-925 -350);
PAINT SKYBLUE (-925 -350);
FORCEPROP 1 LAST PACK_TYPE 0402
J 0
(-925 -450);
DISPLAY 0.510638 (-925 -450);
PAINT SKYBLUE (-925 -450);
FORCEPROP 2 LAST CDS_LIB pure_quanta
J 0
(-975 -300);
DISPLAY INVISIBLE (-975 -300);
FORCEPROP 1 LAST PATH I157
J 0
(-925 -150);
DISPLAY 0.978723 (-925 -150);
PAINT WHITE (-925 -150);
DISPLAY INVISIBLE (-925 -150);
FORCEPROP 1 LAST LOCATION C79
J 0
(-925 -200);
DISPLAY 0.702128 (-925 -200);
PAINT YELLOW (-925 -200);
FORCEPROP 1 LASTPIN (-975 -200) $PN 1
J 0
(-965 -220);
DISPLAY 0.808511 (-965 -220);
PAINT WHITE (-965 -220);
FORCEPROP 1 LASTPIN (-975 -400) $PN 2
J 0
(-965 -420);
DISPLAY 0.808511 (-965 -420);
PAINT WHITE (-965 -420);
FORCEPROP 2 LAST $SEC 1
J 0
(-925 -100);
DISPLAY 0.680851 (-925 -100);
PAINT MONO (-925 -100);
DISPLAY INVISIBLE (-925 -100);
FORCEPROP 0 LAST CDS_SEC 1
J 0
(-925 -100);
DISPLAY 0.680851 (-925 -100);
PAINT MONO (-925 -100);
DISPLAY INVISIBLE (-925 -100);
FORCEADD Q_INDUCTOR..1
(-1475 -100);
FORCEPROP 2 LAST PACK_TYPE SMLF
J 0
(-1600 100);
DISPLAY 0.510638 (-1600 100);
PAINT SKYBLUE (-1600 100);
FORCEPROP 1 LAST MATERIAL IND
J 0
(-1600 -45);
DISPLAY 0.510638 (-1600 -45);
PAINT SKYBLUE (-1600 -45);
FORCEPROP 1 LAST PART_NUMBER CX8PG121009
J 0
(-1600 10);
DISPLAY 0.510638 (-1600 10);
PAINT WHITE (-1600 10);
FORCEPROP 2 LAST VALUE BLM18PG121SN1D/2000MA
J 0
(-1600 150);
DISPLAY 0.510638 (-1600 150);
PAINT SKYBLUE (-1600 150);
FORCEPROP 2 LAST CDS_LIB pure_quanta
J 0
(-1475 -100);
DISPLAY INVISIBLE (-1475 -100);
FORCEPROP 1 LAST NEEDS_NO_SIZE TRUE
J 0
(-1475 -100);
DISPLAY 0.468085 (-1475 -100);
PAINT GREEN (-1475 -100);
DISPLAY INVISIBLE (-1475 -100);
FORCEPROP 1 LAST PATH I158
J 0
(-1400 -45);
DISPLAY 0.723404 (-1400 -45);
PAINT GREEN (-1400 -45);
DISPLAY INVISIBLE (-1400 -45);
FORCEPROP 1 LAST LOCATION L13
J 0
(-1600 60);
DISPLAY 0.702128 (-1600 60);
PAINT YELLOW (-1600 60);
FORCEPROP 2 LASTPIN (-1575 -125) $PN 1
J 2
(-1585 -115);
DISPLAY 0.808511 (-1585 -115);
PAINT WHITE (-1585 -115);
FORCEPROP 2 LASTPIN (-1375 -125) $PN 2
J 0
(-1365 -115);
DISPLAY 0.808511 (-1365 -115);
PAINT WHITE (-1365 -115);
FORCEPROP 2 LAST $SEC 1
J 0
(-1600 200);
DISPLAY 0.680851 (-1600 200);
PAINT MONO (-1600 200);
DISPLAY INVISIBLE (-1600 200);
FORCEPROP 0 LAST CDS_SEC 1
J 0
(-1600 200);
DISPLAY 0.680851 (-1600 200);
PAINT MONO (-1600 200);
DISPLAY INVISIBLE (-1600 200);
FORCEADD UNIVERSAL_POWER..1
(-1775 -50);
FORCEPROP 3 LASTPIN (-1775 -100) SIG_NAME P1V0_AUX\g
J 0
(-1765 -90);
DISPLAY 0.659574 (-1765 -90);
PAINT MONO (-1765 -90);
DISPLAY INVISIBLE (-1765 -90);
FORCEPROP 1 LAST HDL_POWER P1V0_AUX
J 1
(-1775 0);
DISPLAY 0.702128 (-1775 0);
PAINT GREEN (-1775 0);
FORCEPROP 2 LAST CDS_LIB logical_power
J 0
(-1775 -50);
DISPLAY INVISIBLE (-1775 -50);
FORCEPROP 1 LAST PATH I159
J 0
(-1725 -25);
DISPLAY 0.872340 (-1725 -25);
PAINT AQUA (-1725 -25);
DISPLAY INVISIBLE (-1725 -25);
FORCEADD Q_CAP..1
(-1175 -300);
FORCEPROP 1 LAST PART_NUMBER CH5104KEB02
R 3
J 0
(-1250 -150);
DISPLAY 0.510638 (-1250 -150);
PAINT WHITE (-1250 -150);
FORCEPROP 1 LAST VOLTAGE 25V
J 0
(-1125 -300);
DISPLAY 0.510638 (-1125 -300);
PAINT SKYBLUE (-1125 -300);
FORCEPROP 1 LAST VALUE 1UF
J 0
(-1125 -250);
DISPLAY 0.510638 (-1125 -250);
PAINT SKYBLUE (-1125 -250);
FORCEPROP 1 LAST MATERIAL X6S
J 0
(-1125 -400);
DISPLAY 0.510638 (-1125 -400);
PAINT SKYBLUE (-1125 -400);
FORCEPROP 1 LAST TOLERANCE 10%
J 0
(-1125 -350);
DISPLAY 0.510638 (-1125 -350);
PAINT SKYBLUE (-1125 -350);
FORCEPROP 1 LAST PACK_TYPE C0402
J 0
(-1150 -450);
DISPLAY 0.510638 (-1150 -450);
PAINT SKYBLUE (-1150 -450);
FORCEPROP 2 LAST CDS_LIB pure_quanta
J 0
(-1175 -300);
DISPLAY INVISIBLE (-1175 -300);
FORCEPROP 1 LAST PATH I160
J 0
(-1125 -150);
DISPLAY 0.978723 (-1125 -150);
PAINT WHITE (-1125 -150);
DISPLAY INVISIBLE (-1125 -150);
FORCEPROP 1 LAST LOCATION C78
J 0
(-1125 -200);
DISPLAY 0.702128 (-1125 -200);
PAINT YELLOW (-1125 -200);
FORCEPROP 1 LASTPIN (-1175 -200) $PN 1
J 0
(-1165 -220);
DISPLAY 0.808511 (-1165 -220);
PAINT WHITE (-1165 -220);
FORCEPROP 1 LASTPIN (-1175 -400) $PN 2
J 0
(-1165 -420);
DISPLAY 0.808511 (-1165 -420);
PAINT WHITE (-1165 -420);
FORCEPROP 2 LAST $SEC 1
J 0
(-1125 -100);
DISPLAY 0.680851 (-1125 -100);
PAINT MONO (-1125 -100);
DISPLAY INVISIBLE (-1125 -100);
FORCEPROP 0 LAST CDS_SEC 1
J 0
(-1125 -100);
DISPLAY 0.680851 (-1125 -100);
PAINT MONO (-1125 -100);
DISPLAY INVISIBLE (-1125 -100);
FORCEADD UNIVERSAL_GND..1
(-1075 -575);
FORCEPROP 3 LASTPIN (-1075 -525) SIG_NAME GND\g
J 0
(-1065 -515);
DISPLAY 0.659574 (-1065 -515);
PAINT MONO (-1065 -515);
DISPLAY INVISIBLE (-1065 -515);
FORCEPROP 2 LAST CDS_LIB logical_power
J 0
(-1075 -575);
DISPLAY INVISIBLE (-1075 -575);
FORCEPROP 1 LAST HDL_POWER GND
J 1
(-1050 -650);
DISPLAY 0.702128 (-1050 -650);
PAINT GREEN (-1050 -650);
DISPLAY INVISIBLE (-1050 -650);
FORCEPROP 1 LAST PATH I161
J 0
(-1000 -575);
DISPLAY 0.872340 (-1000 -575);
PAINT AQUA (-1000 -575);
DISPLAY INVISIBLE (-1000 -575);
FORCEADD OFFPAGE..2
(4050 2175);
FORCEPROP 2 LAST $XR0 16 
J 0
(4239 2175);
DISPLAY 0.638298 (4239 2175);
PAINT MONO (4239 2175);
FORCEPROP 2 LAST CDS_LIB standard
J 0
(4050 2175);
DISPLAY INVISIBLE (4050 2175);
FORCEPROP 1 LAST OFFPAGE TRUE
J 0
(4375 2050);
DISPLAY 0.872340 (4375 2050);
PAINT GREEN (4375 2050);
DISPLAY INVISIBLE (4375 2050);
FORCEPROP 1 LAST COMMENT_BODY TRUE
J 0
(4005 2080);
DISPLAY 0.872340 (4005 2080);
PAINT PEACH (4005 2080);
DISPLAY INVISIBLE (4005 2080);
FORCEPROP 2 LAST PATH I162
J 0
(4250 2225);
DISPLAY 1.021277 (4250 2225);
DISPLAY INVISIBLE (4250 2225);
FORCEADD Q_CAP..1
(3625 2000);
FORCEPROP 1 LAST VALUE 0.1UF
J 0
(3675 2050);
DISPLAY 0.510638 (3675 2050);
PAINT SKYBLUE (3675 2050);
FORCEPROP 1 LAST VOLTAGE 25V
J 0
(3675 2000);
DISPLAY 0.510638 (3675 2000);
PAINT SKYBLUE (3675 2000);
FORCEPROP 1 LAST PART_NUMBER CH4104K1B00
J 0
(3675 1800);
DISPLAY 0.510638 (3675 1800);
PAINT WHITE (3675 1800);
FORCEPROP 1 LAST MATERIAL X7R
J 0
(3675 1900);
DISPLAY 0.510638 (3675 1900);
PAINT SKYBLUE (3675 1900);
FORCEPROP 1 LAST TOLERANCE 10%
J 0
(3675 1950);
DISPLAY 0.510638 (3675 1950);
PAINT SKYBLUE (3675 1950);
FORCEPROP 1 LAST PACK_TYPE 0402
J 0
(3675 1850);
DISPLAY 0.510638 (3675 1850);
PAINT SKYBLUE (3675 1850);
FORCEPROP 2 LAST CDS_LIB pure_quanta
J 0
(3625 2000);
DISPLAY INVISIBLE (3625 2000);
FORCEPROP 1 LAST PATH I163
J 0
(3675 2150);
DISPLAY 0.978723 (3675 2150);
PAINT WHITE (3675 2150);
DISPLAY INVISIBLE (3675 2150);
FORCEPROP 1 LAST LOCATION C130
J 0
(3675 2100);
DISPLAY 0.702128 (3675 2100);
PAINT YELLOW (3675 2100);
FORCEPROP 1 LASTPIN (3625 2100) $PN 1
J 0
(3635 2080);
DISPLAY 0.808511 (3635 2080);
PAINT WHITE (3635 2080);
FORCEPROP 1 LASTPIN (3625 1900) $PN 2
J 0
(3635 1880);
DISPLAY 0.808511 (3635 1880);
PAINT WHITE (3635 1880);
FORCEPROP 2 LAST $SEC 1
J 0
(3675 2200);
DISPLAY 0.680851 (3675 2200);
PAINT MONO (3675 2200);
DISPLAY INVISIBLE (3675 2200);
FORCEPROP 0 LAST CDS_SEC 1
J 0
(3675 2200);
DISPLAY 0.680851 (3675 2200);
PAINT MONO (3675 2200);
DISPLAY INVISIBLE (3675 2200);
FORCEADD UNIVERSAL_GND..1
(3525 1725);
FORCEPROP 3 LASTPIN (3525 1775) SIG_NAME GND\g
J 0
(3535 1785);
DISPLAY 0.659574 (3535 1785);
PAINT MONO (3535 1785);
DISPLAY INVISIBLE (3535 1785);
FORCEPROP 2 LAST CDS_LIB logical_power
J 0
(3525 1725);
DISPLAY INVISIBLE (3525 1725);
FORCEPROP 1 LAST HDL_POWER GND
J 1
(3550 1650);
DISPLAY 0.702128 (3550 1650);
PAINT GREEN (3550 1650);
DISPLAY INVISIBLE (3550 1650);
FORCEPROP 1 LAST PATH I164
J 0
(3600 1725);
DISPLAY 0.872340 (3600 1725);
PAINT AQUA (3600 1725);
DISPLAY INVISIBLE (3600 1725);
FORCEADD Q_CAP..1
(3425 2000);
FORCEPROP 1 LAST VALUE 1UF
J 0
(3475 2050);
DISPLAY 0.510638 (3475 2050);
PAINT SKYBLUE (3475 2050);
FORCEPROP 1 LAST PART_NUMBER CH5104KEB02
R 3
J 0
(3325 2150);
DISPLAY 0.510638 (3325 2150);
PAINT WHITE (3325 2150);
FORCEPROP 1 LAST VOLTAGE 25V
J 0
(3475 2000);
DISPLAY 0.510638 (3475 2000);
PAINT SKYBLUE (3475 2000);
FORCEPROP 1 LAST MATERIAL X6S
J 0
(3475 1900);
DISPLAY 0.510638 (3475 1900);
PAINT SKYBLUE (3475 1900);
FORCEPROP 1 LAST TOLERANCE 10%
J 0
(3475 1950);
DISPLAY 0.510638 (3475 1950);
PAINT SKYBLUE (3475 1950);
FORCEPROP 1 LAST PACK_TYPE C0402
J 0
(3450 1850);
DISPLAY 0.510638 (3450 1850);
PAINT SKYBLUE (3450 1850);
FORCEPROP 2 LAST CDS_LIB pure_quanta
J 0
(3425 2000);
DISPLAY INVISIBLE (3425 2000);
FORCEPROP 1 LAST PATH I165
J 0
(3475 2150);
DISPLAY 0.978723 (3475 2150);
PAINT WHITE (3475 2150);
DISPLAY INVISIBLE (3475 2150);
FORCEPROP 1 LAST LOCATION C128
J 0
(3475 2100);
DISPLAY 0.702128 (3475 2100);
PAINT YELLOW (3475 2100);
FORCEPROP 1 LASTPIN (3425 2100) $PN 1
J 0
(3435 2080);
DISPLAY 0.808511 (3435 2080);
PAINT WHITE (3435 2080);
FORCEPROP 1 LASTPIN (3425 1900) $PN 2
J 0
(3435 1880);
DISPLAY 0.808511 (3435 1880);
PAINT WHITE (3435 1880);
FORCEPROP 2 LAST $SEC 1
J 0
(3475 2200);
DISPLAY 0.680851 (3475 2200);
PAINT MONO (3475 2200);
DISPLAY INVISIBLE (3475 2200);
FORCEPROP 0 LAST CDS_SEC 1
J 0
(3475 2200);
DISPLAY 0.680851 (3475 2200);
PAINT MONO (3475 2200);
DISPLAY INVISIBLE (3475 2200);
FORCEADD Q_INDUCTOR..1
(3125 2200);
FORCEPROP 1 LAST MATERIAL IND
J 0
(3000 2255);
DISPLAY 0.510638 (3000 2255);
PAINT SKYBLUE (3000 2255);
FORCEPROP 2 LAST PACK_TYPE SMLF
J 0
(3000 2400);
DISPLAY 0.510638 (3000 2400);
PAINT SKYBLUE (3000 2400);
FORCEPROP 2 LAST VALUE BLM18PG121SN1D/2000MA
J 0
(3000 2450);
DISPLAY 0.510638 (3000 2450);
PAINT SKYBLUE (3000 2450);
FORCEPROP 1 LAST PART_NUMBER CX8PG121009
J 0
(3000 2310);
DISPLAY 0.510638 (3000 2310);
PAINT WHITE (3000 2310);
FORCEPROP 1 LAST NEEDS_NO_SIZE TRUE
J 0
(3125 2200);
DISPLAY 0.468085 (3125 2200);
PAINT GREEN (3125 2200);
DISPLAY INVISIBLE (3125 2200);
FORCEPROP 2 LAST CDS_LIB pure_quanta
J 0
(3125 2200);
DISPLAY INVISIBLE (3125 2200);
FORCEPROP 1 LAST PATH I166
J 0
(3200 2255);
DISPLAY 0.723404 (3200 2255);
PAINT GREEN (3200 2255);
DISPLAY INVISIBLE (3200 2255);
FORCEPROP 1 LAST LOCATION L16
J 0
(3000 2360);
DISPLAY 0.702128 (3000 2360);
PAINT YELLOW (3000 2360);
FORCEPROP 2 LASTPIN (3025 2175) $PN 1
J 2
(3015 2185);
DISPLAY 0.808511 (3015 2185);
PAINT WHITE (3015 2185);
FORCEPROP 2 LASTPIN (3225 2175) $PN 2
J 0
(3235 2185);
DISPLAY 0.808511 (3235 2185);
PAINT WHITE (3235 2185);
FORCEPROP 2 LAST $SEC 1
J 0
(3000 2500);
DISPLAY 0.680851 (3000 2500);
PAINT MONO (3000 2500);
DISPLAY INVISIBLE (3000 2500);
FORCEPROP 0 LAST CDS_SEC 1
J 0
(3000 2500);
DISPLAY 0.680851 (3000 2500);
PAINT MONO (3000 2500);
DISPLAY INVISIBLE (3000 2500);
FORCEADD UNIVERSAL_POWER..1
(2825 2250);
FORCEPROP 3 LASTPIN (2825 2200) SIG_NAME P1V8_AUX\g
J 0
(2835 2210);
DISPLAY 0.659574 (2835 2210);
PAINT MONO (2835 2210);
DISPLAY INVISIBLE (2835 2210);
FORCEPROP 1 LAST HDL_POWER P1V8_AUX
J 1
(2825 2300);
DISPLAY 0.702128 (2825 2300);
PAINT GREEN (2825 2300);
FORCEPROP 2 LAST CDS_LIB logical_power
J 0
(2825 2250);
DISPLAY INVISIBLE (2825 2250);
FORCEPROP 1 LAST PATH I167
J 0
(2875 2275);
DISPLAY 0.872340 (2875 2275);
PAINT AQUA (2875 2275);
DISPLAY INVISIBLE (2875 2275);
FORCEADD OFFPAGE..2
(2675 2125);
FORCEPROP 2 LAST $XR0 16 
J 0
(2864 2125);
DISPLAY 0.638298 (2864 2125);
PAINT MONO (2864 2125);
FORCEPROP 2 LAST CDS_LIB standard
J 0
(2675 2125);
DISPLAY INVISIBLE (2675 2125);
FORCEPROP 1 LAST OFFPAGE TRUE
J 0
(3000 2000);
DISPLAY 0.872340 (3000 2000);
PAINT GREEN (3000 2000);
DISPLAY INVISIBLE (3000 2000);
FORCEPROP 1 LAST COMMENT_BODY TRUE
J 0
(2630 2030);
DISPLAY 0.872340 (2630 2030);
PAINT PEACH (2630 2030);
DISPLAY INVISIBLE (2630 2030);
FORCEPROP 2 LAST PATH I168
J 0
(2875 2175);
DISPLAY 1.021277 (2875 2175);
DISPLAY INVISIBLE (2875 2175);
FORCEADD Q_CAP..1
(2250 1950);
FORCEPROP 1 LAST VOLTAGE 25V
J 0
(2300 1950);
DISPLAY 0.510638 (2300 1950);
PAINT SKYBLUE (2300 1950);
FORCEPROP 1 LAST PART_NUMBER CH4104K1B00
J 0
(2300 1750);
DISPLAY 0.510638 (2300 1750);
PAINT WHITE (2300 1750);
FORCEPROP 1 LAST MATERIAL X7R
J 0
(2300 1850);
DISPLAY 0.510638 (2300 1850);
PAINT SKYBLUE (2300 1850);
FORCEPROP 1 LAST TOLERANCE 10%
J 0
(2300 1900);
DISPLAY 0.510638 (2300 1900);
PAINT SKYBLUE (2300 1900);
FORCEPROP 1 LAST VALUE 0.1UF
J 0
(2300 2000);
DISPLAY 0.510638 (2300 2000);
PAINT SKYBLUE (2300 2000);
FORCEPROP 1 LAST PACK_TYPE 0402
J 0
(2300 1800);
DISPLAY 0.510638 (2300 1800);
PAINT SKYBLUE (2300 1800);
FORCEPROP 2 LAST CDS_LIB pure_quanta
J 0
(2250 1950);
DISPLAY INVISIBLE (2250 1950);
FORCEPROP 1 LAST PATH I169
J 0
(2300 2100);
DISPLAY 0.978723 (2300 2100);
PAINT WHITE (2300 2100);
DISPLAY INVISIBLE (2300 2100);
FORCEPROP 1 LAST LOCATION C97
J 0
(2300 2050);
DISPLAY 0.702128 (2300 2050);
PAINT YELLOW (2300 2050);
FORCEPROP 1 LASTPIN (2250 2050) $PN 1
J 0
(2260 2030);
DISPLAY 0.808511 (2260 2030);
PAINT WHITE (2260 2030);
FORCEPROP 1 LASTPIN (2250 1850) $PN 2
J 0
(2260 1830);
DISPLAY 0.808511 (2260 1830);
PAINT WHITE (2260 1830);
FORCEPROP 2 LAST $SEC 1
J 0
(2300 2150);
DISPLAY 0.680851 (2300 2150);
PAINT MONO (2300 2150);
DISPLAY INVISIBLE (2300 2150);
FORCEPROP 0 LAST CDS_SEC 1
J 0
(2300 2150);
DISPLAY 0.680851 (2300 2150);
PAINT MONO (2300 2150);
DISPLAY INVISIBLE (2300 2150);
FORCEADD Q_INDUCTOR..1
(1750 2150);
FORCEPROP 1 LAST PART_NUMBER CX8PG121009
J 0
(1625 2260);
DISPLAY 0.510638 (1625 2260);
PAINT WHITE (1625 2260);
FORCEPROP 2 LAST VALUE BLM18PG121SN1D/2000MA
J 0
(1625 2400);
DISPLAY 0.510638 (1625 2400);
PAINT SKYBLUE (1625 2400);
FORCEPROP 2 LAST PACK_TYPE SMLF
J 0
(1625 2350);
DISPLAY 0.510638 (1625 2350);
PAINT SKYBLUE (1625 2350);
FORCEPROP 1 LAST MATERIAL IND
J 0
(1625 2205);
DISPLAY 0.510638 (1625 2205);
PAINT SKYBLUE (1625 2205);
FORCEPROP 1 LAST NEEDS_NO_SIZE TRUE
J 0
(1750 2150);
DISPLAY 0.468085 (1750 2150);
PAINT GREEN (1750 2150);
DISPLAY INVISIBLE (1750 2150);
FORCEPROP 2 LAST CDS_LIB pure_quanta
J 0
(1750 2150);
DISPLAY INVISIBLE (1750 2150);
FORCEPROP 1 LAST PATH I170
J 0
(1825 2205);
DISPLAY 0.723404 (1825 2205);
PAINT GREEN (1825 2205);
DISPLAY INVISIBLE (1825 2205);
FORCEPROP 1 LAST LOCATION L15
J 0
(1625 2310);
DISPLAY 0.702128 (1625 2310);
PAINT YELLOW (1625 2310);
FORCEPROP 2 LASTPIN (1650 2125) $PN 1
J 2
(1640 2135);
DISPLAY 0.808511 (1640 2135);
PAINT WHITE (1640 2135);
FORCEPROP 2 LASTPIN (1850 2125) $PN 2
J 0
(1860 2135);
DISPLAY 0.808511 (1860 2135);
PAINT WHITE (1860 2135);
FORCEPROP 2 LAST $SEC 1
J 0
(1625 2450);
DISPLAY 0.680851 (1625 2450);
PAINT MONO (1625 2450);
DISPLAY INVISIBLE (1625 2450);
FORCEPROP 0 LAST CDS_SEC 1
J 0
(1625 2450);
DISPLAY 0.680851 (1625 2450);
PAINT MONO (1625 2450);
DISPLAY INVISIBLE (1625 2450);
FORCEADD UNIVERSAL_POWER..1
(1450 2200);
FORCEPROP 3 LASTPIN (1450 2150) SIG_NAME P1V0_AUX\g
J 0
(1460 2160);
DISPLAY 0.659574 (1460 2160);
PAINT MONO (1460 2160);
DISPLAY INVISIBLE (1460 2160);
FORCEPROP 1 LAST HDL_POWER P1V0_AUX
J 1
(1450 2250);
DISPLAY 0.702128 (1450 2250);
PAINT GREEN (1450 2250);
FORCEPROP 2 LAST CDS_LIB logical_power
J 0
(1450 2200);
DISPLAY INVISIBLE (1450 2200);
FORCEPROP 1 LAST PATH I171
J 0
(1500 2225);
DISPLAY 0.872340 (1500 2225);
PAINT AQUA (1500 2225);
DISPLAY INVISIBLE (1500 2225);
FORCEADD UNIVERSAL_GND..1
(2150 1675);
FORCEPROP 3 LASTPIN (2150 1725) SIG_NAME GND\g
J 0
(2160 1735);
DISPLAY 0.659574 (2160 1735);
PAINT MONO (2160 1735);
DISPLAY INVISIBLE (2160 1735);
FORCEPROP 2 LAST CDS_LIB logical_power
J 0
(2150 1675);
DISPLAY INVISIBLE (2150 1675);
FORCEPROP 1 LAST HDL_POWER GND
J 1
(2175 1600);
DISPLAY 0.702128 (2175 1600);
PAINT GREEN (2175 1600);
DISPLAY INVISIBLE (2175 1600);
FORCEPROP 1 LAST PATH I172
J 0
(2225 1675);
DISPLAY 0.872340 (2225 1675);
PAINT AQUA (2225 1675);
DISPLAY INVISIBLE (2225 1675);
FORCEADD Q_CAP..1
(2050 1950);
FORCEPROP 1 LAST VOLTAGE 25V
J 0
(2100 1950);
DISPLAY 0.510638 (2100 1950);
PAINT SKYBLUE (2100 1950);
FORCEPROP 1 LAST VALUE 1UF
J 0
(2100 2000);
DISPLAY 0.510638 (2100 2000);
PAINT SKYBLUE (2100 2000);
FORCEPROP 1 LAST PART_NUMBER CH5104KEB02
R 3
J 0
(1975 2100);
DISPLAY 0.510638 (1975 2100);
PAINT WHITE (1975 2100);
FORCEPROP 1 LAST MATERIAL X6S
J 0
(2100 1850);
DISPLAY 0.510638 (2100 1850);
PAINT SKYBLUE (2100 1850);
FORCEPROP 1 LAST TOLERANCE 10%
J 0
(2100 1900);
DISPLAY 0.510638 (2100 1900);
PAINT SKYBLUE (2100 1900);
FORCEPROP 1 LAST PACK_TYPE C0402
J 0
(2075 1800);
DISPLAY 0.510638 (2075 1800);
PAINT SKYBLUE (2075 1800);
FORCEPROP 2 LAST CDS_LIB pure_quanta
J 0
(2050 1950);
DISPLAY INVISIBLE (2050 1950);
FORCEPROP 1 LAST PATH I173
J 0
(2100 2100);
DISPLAY 0.978723 (2100 2100);
PAINT WHITE (2100 2100);
DISPLAY INVISIBLE (2100 2100);
FORCEPROP 1 LAST LOCATION C90
J 0
(2100 2050);
DISPLAY 0.702128 (2100 2050);
PAINT YELLOW (2100 2050);
FORCEPROP 1 LASTPIN (2050 2050) $PN 1
J 0
(2060 2030);
DISPLAY 0.808511 (2060 2030);
PAINT WHITE (2060 2030);
FORCEPROP 1 LASTPIN (2050 1850) $PN 2
J 0
(2060 1830);
DISPLAY 0.808511 (2060 1830);
PAINT WHITE (2060 1830);
FORCEPROP 2 LAST $SEC 1
J 0
(2100 2150);
DISPLAY 0.680851 (2100 2150);
PAINT MONO (2100 2150);
DISPLAY INVISIBLE (2100 2150);
FORCEPROP 0 LAST CDS_SEC 1
J 0
(2100 2150);
DISPLAY 0.680851 (2100 2150);
PAINT MONO (2100 2150);
DISPLAY INVISIBLE (2100 2150);
FORCEADD UNIVERSAL_POWER..1
(1600 550);
FORCEPROP 3 LASTPIN (1600 500) SIG_NAME PGPPA_BMC_AUX\g
J 0
(1610 510);
DISPLAY 0.659574 (1610 510);
PAINT MONO (1610 510);
DISPLAY INVISIBLE (1610 510);
FORCEPROP 1 LAST HDL_POWER PGPPA_BMC_AUX
J 1
(1600 600);
DISPLAY 0.702128 (1600 600);
PAINT GREEN (1600 600);
FORCEPROP 2 LAST CDS_LIB logical_power
J 0
(1600 550);
DISPLAY INVISIBLE (1600 550);
FORCEPROP 1 LAST PATH I174
J 0
(1650 575);
DISPLAY 0.872340 (1650 575);
PAINT AQUA (1650 575);
DISPLAY INVISIBLE (1650 575);
FORCEADD Q_INDUCTOR..1
R 2
(2325 450);
FORCEPROP 1 LAST MATERIAL IND
J 2
(2450 500);
DISPLAY 0.510638 (2450 500);
PAINT SKYBLUE (2450 500);
FORCEPROP 2 LAST PACK_TYPE SMLF
J 2
(2350 625);
DISPLAY 0.510638 (2350 625);
PAINT SKYBLUE (2350 625);
FORCEPROP 1 LAST PART_NUMBER CX8EG121000
J 2
(2450 560);
DISPLAY 0.510638 (2450 560);
PAINT WHITE (2450 560);
FORCEPROP 2 LAST VALUE BLM18EG121SN1D/2A
J 2
(2350 500);
DISPLAY 0.510638 (2350 500);
PAINT SKYBLUE (2350 500);
FORCEPROP 1 LAST NEEDS_NO_SIZE TRUE
J 2
(2325 450);
DISPLAY 0.468085 (2325 450);
PAINT GREEN (2325 450);
DISPLAY INVISIBLE (2325 450);
FORCEPROP 2 LAST CDS_LIB pure_quanta
J 2
(2325 450);
DISPLAY INVISIBLE (2325 450);
FORCEPROP 1 LAST PATH I176
J 2
(2250 505);
DISPLAY 0.723404 (2250 505);
PAINT GREEN (2250 505);
DISPLAY INVISIBLE (2250 505);
FORCEPROP 1 LAST LOCATION L17
J 2
(2450 610);
DISPLAY 0.702128 (2450 610);
PAINT YELLOW (2450 610);
FORCEPROP 0 LASTPIN (2425 425) $PN 1
J 0
(2435 435);
DISPLAY 0.808511 (2435 435);
PAINT WHITE (2435 435);
FORCEPROP 0 LASTPIN (2225 425) $PN 2
J 2
(2215 435);
DISPLAY 0.808511 (2215 435);
PAINT WHITE (2215 435);
FORCEPROP 0 LAST $SEC 1
J 0
(2450 650);
DISPLAY INVISIBLE (2450 650);
FORCEPROP 0 LAST CDS_SEC 1
J 0
(2450 650);
DISPLAY INVISIBLE (2450 650);
FORCEADD Q_CAP..1
(2050 250);
FORCEPROP 1 LAST PART_NUMBER CH4104K1B00
J 0
(2100 50);
DISPLAY 0.510638 (2100 50);
PAINT WHITE (2100 50);
FORCEPROP 1 LAST MATERIAL X7R
J 0
(2100 150);
DISPLAY 0.510638 (2100 150);
PAINT SKYBLUE (2100 150);
FORCEPROP 1 LAST TOLERANCE 10%
J 0
(2100 200);
DISPLAY 0.510638 (2100 200);
PAINT SKYBLUE (2100 200);
FORCEPROP 1 LAST PACK_TYPE 0402
J 0
(2100 100);
DISPLAY 0.510638 (2100 100);
PAINT SKYBLUE (2100 100);
FORCEPROP 1 LAST VOLTAGE 25V
J 0
(2100 250);
DISPLAY 0.510638 (2100 250);
PAINT SKYBLUE (2100 250);
FORCEPROP 1 LAST VALUE 0.1UF
J 0
(2100 300);
DISPLAY 0.510638 (2100 300);
PAINT SKYBLUE (2100 300);
FORCEPROP 2 LAST CDS_LIB pure_quanta
J 0
(2050 250);
DISPLAY INVISIBLE (2050 250);
FORCEPROP 1 LAST PATH I178
J 0
(2100 400);
DISPLAY 0.978723 (2100 400);
PAINT WHITE (2100 400);
DISPLAY INVISIBLE (2100 400);
FORCEPROP 1 LAST LOCATION C96
J 0
(2100 350);
DISPLAY 0.702128 (2100 350);
PAINT YELLOW (2100 350);
FORCEPROP 1 LASTPIN (2050 350) $PN 1
J 0
(2060 330);
DISPLAY 0.808511 (2060 330);
PAINT WHITE (2060 330);
FORCEPROP 1 LASTPIN (2050 150) $PN 2
J 0
(2060 130);
DISPLAY 0.808511 (2060 130);
PAINT WHITE (2060 130);
FORCEPROP 0 LAST $SEC 1
J 0
(2100 400);
DISPLAY 0.680851 (2100 400);
PAINT MONO (2100 400);
DISPLAY INVISIBLE (2100 400);
FORCEPROP 0 LAST CDS_SEC 1
J 0
(2100 400);
DISPLAY 0.680851 (2100 400);
DISPLAY INVISIBLE (2100 400);
FORCEADD UNIVERSAL_GND..1
(2050 0);
FORCEPROP 3 LASTPIN (2050 50) SIG_NAME GND\g
J 0
(2060 60);
DISPLAY 0.659574 (2060 60);
PAINT MONO (2060 60);
DISPLAY INVISIBLE (2060 60);
FORCEPROP 2 LAST CDS_LIB logical_power
J 0
(2050 0);
DISPLAY INVISIBLE (2050 0);
FORCEPROP 1 LAST HDL_POWER GND
J 1
(2075 -75);
DISPLAY 0.702128 (2075 -75);
PAINT GREEN (2075 -75);
DISPLAY INVISIBLE (2075 -75);
FORCEPROP 1 LAST PATH I179
J 0
(2125 0);
DISPLAY 0.872340 (2125 0);
PAINT AQUA (2125 0);
DISPLAY INVISIBLE (2125 0);
FORCEADD Q_CAP..1
(1650 250);
FORCEPROP 1 LAST PART_NUMBER CH6101MEB01
J 0
(1700 100);
DISPLAY 0.510638 (1700 100);
PAINT WHITE (1700 100);
FORCEPROP 1 LAST VOLTAGE 6.3V
J 0
(1700 250);
DISPLAY 0.510638 (1700 250);
PAINT SKYBLUE (1700 250);
FORCEPROP 1 LAST MATERIAL X6S
J 0
(1700 150);
DISPLAY 0.510638 (1700 150);
PAINT SKYBLUE (1700 150);
FORCEPROP 1 LAST TOLERANCE 20%
J 0
(1700 200);
DISPLAY 0.510638 (1700 200);
PAINT SKYBLUE (1700 200);
FORCEPROP 1 LAST VALUE 10UF
J 0
(1700 300);
DISPLAY 0.510638 (1700 300);
PAINT SKYBLUE (1700 300);
FORCEPROP 1 LAST PACK_TYPE C0402
J 0
(1700 50);
DISPLAY 0.510638 (1700 50);
PAINT SKYBLUE (1700 50);
FORCEPROP 2 LAST CDS_LIB pure_quanta
J 0
(1650 250);
DISPLAY INVISIBLE (1650 250);
FORCEPROP 1 LAST PATH I180
J 0
(1700 400);
DISPLAY 0.978723 (1700 400);
PAINT WHITE (1700 400);
DISPLAY INVISIBLE (1700 400);
FORCEPROP 1 LAST LOCATION C224
J 0
(1700 350);
DISPLAY 0.702128 (1700 350);
PAINT YELLOW (1700 350);
FORCEPROP 1 LASTPIN (1650 350) $PN 1
J 0
(1660 330);
DISPLAY 0.808511 (1660 330);
PAINT WHITE (1660 330);
FORCEPROP 1 LASTPIN (1650 150) $PN 2
J 0
(1660 130);
DISPLAY 0.808511 (1660 130);
PAINT WHITE (1660 130);
FORCEPROP 0 LAST $SEC 1
J 0
(1700 400);
DISPLAY INVISIBLE (1700 400);
FORCEPROP 0 LAST CDS_SEC 1
J 0
(1700 450);
DISPLAY 0.680851 (1700 450);
PAINT MONO (1700 450);
DISPLAY INVISIBLE (1700 450);
FORCEADD UNIVERSAL_GND..1
(1650 50);
FORCEPROP 3 LASTPIN (1650 100) SIG_NAME GND\g
J 0
(1660 110);
DISPLAY 0.659574 (1660 110);
PAINT MONO (1660 110);
DISPLAY INVISIBLE (1660 110);
FORCEPROP 2 LAST CDS_LIB logical_power
J 0
(1650 50);
DISPLAY INVISIBLE (1650 50);
FORCEPROP 1 LAST HDL_POWER GND
J 1
(1675 -25);
DISPLAY 0.702128 (1675 -25);
PAINT GREEN (1675 -25);
DISPLAY INVISIBLE (1675 -25);
FORCEPROP 1 LAST PATH I181
J 0
(1725 50);
DISPLAY 0.872340 (1725 50);
PAINT AQUA (1725 50);
DISPLAY INVISIBLE (1725 50);
FORCEADD UNIVERSAL_GND..1
(-2300 -625);
FORCEPROP 3 LASTPIN (-2300 -575) SIG_NAME GND\g
J 0
(-2290 -565);
DISPLAY 0.659574 (-2290 -565);
PAINT MONO (-2290 -565);
DISPLAY INVISIBLE (-2290 -565);
FORCEPROP 2 LAST CDS_LIB logical_power
J 0
(-2300 -625);
DISPLAY INVISIBLE (-2300 -625);
FORCEPROP 1 LAST HDL_POWER GND
J 1
(-2275 -700);
DISPLAY 0.702128 (-2275 -700);
PAINT GREEN (-2275 -700);
DISPLAY INVISIBLE (-2275 -700);
FORCEPROP 1 LAST PATH I2
J 0
(-2225 -625);
DISPLAY 0.872340 (-2225 -625);
PAINT AQUA (-2225 -625);
DISPLAY INVISIBLE (-2225 -625);
FORCEADD MOSFET_N_GSD..1
R 2
(2850 -1125);
FORCEPROP 1 LAST PART_NUMBER BAM69680000
J 2
(2749 -1145);
DISPLAY 0.510638 (2749 -1145);
PAINT WHITE (2749 -1145);
FORCEPROP 2 LAST PART_TYPE SMLF
J 2
(2725 -975);
DISPLAY 0.510638 (2725 -975);
PAINT SKYBLUE (2725 -975);
FORCEPROP 1 LAST MATERIAL IC
J 2
(2749 -1225);
DISPLAY 0.510638 (2749 -1225);
PAINT SKYBLUE (2749 -1225);
FORCEPROP 2 LAST VALUE DMG6968U-7
J 2
(2725 -1025);
DISPLAY 0.510638 (2725 -1025);
PAINT SKYBLUE (2725 -1025);
FORCEPROP 2 LAST SEC_TYPE 
J 0
(2725 -950);
DISPLAY 0.680851 (2725 -950);
DISPLAY INVISIBLE (2725 -950);
FORCEPROP 2 LAST CDS_LIB pure_quanta
J 2
(2850 -1125);
DISPLAY INVISIBLE (2850 -1125);
FORCEPROP 1 LAST NEEDS_NO_SIZE TRUE
J 2
(2850 -1125);
DISPLAY 0.468085 (2850 -1125);
PAINT GREEN (2850 -1125);
DISPLAY INVISIBLE (2850 -1125);
FORCEPROP 1 LAST CDS_LMAN_SYM_OUTLINE -100,100,100,-100
J 2
(2850 -1125);
DISPLAY 0.468085 (2850 -1125);
PAINT GREEN (2850 -1125);
DISPLAY INVISIBLE (2850 -1125);
FORCEPROP 1 LAST PATH I227
J 2
(2850 -1125);
DISPLAY 0.723404 (2850 -1125);
PAINT GREEN (2850 -1125);
DISPLAY INVISIBLE (2850 -1125);
FORCEPROP 1 LAST LOCATION Q10
J 2
(2749 -1080);
DISPLAY 0.702128 (2749 -1080);
PAINT YELLOW (2749 -1080);
FORCEPROP 0 LASTPIN (2825 -975) $PN D
R 1
J 0
(2815 -965);
DISPLAY 0.680851 (2815 -965);
PAINT MONO (2815 -965);
FORCEPROP 0 LASTPIN (3025 -1175) $PN G
J 0
(3035 -1165);
DISPLAY 0.680851 (3035 -1165);
PAINT MONO (3035 -1165);
FORCEPROP 0 LASTPIN (2825 -1275) $PN S
R 1
J 2
(2815 -1285);
DISPLAY 0.680851 (2815 -1285);
PAINT MONO (2815 -1285);
FORCEPROP 0 LAST SEC 1
J 0
(2725 -950);
DISPLAY 0.680851 (2725 -950);
PAINT MONO (2725 -950);
DISPLAY INVISIBLE (2725 -950);
FORCEADD Q_RES..1
(3775 -1175);
FORCEPROP 1 LAST MATERIAL CHIP
J 2
(4100 -1175);
DISPLAY 0.510638 (4100 -1175);
PAINT SKYBLUE (4100 -1175);
FORCEPROP 1 LAST VALUE 33.2
J 0
(3900 -1175);
DISPLAY 0.510638 (3900 -1175);
PAINT SKYBLUE (3900 -1175);
FORCEPROP 2 LAST CDS_LIB pure_quanta
J 0
(3775 -1175);
DISPLAY INVISIBLE (3775 -1175);
FORCEPROP 1 LAST PATH I228
J 0
(3725 -1025);
DISPLAY 0.978723 (3725 -1025);
PAINT WHITE (3725 -1025);
DISPLAY INVISIBLE (3725 -1025);
FORCEPROP 1 LAST WATTAGE 1/16W
J 2
(3750 -1325);
DISPLAY 0.510638 (3750 -1325);
PAINT SKYBLUE (3750 -1325);
DISPLAY INVISIBLE (3750 -1325);
FORCEPROP 1 LAST PACK_TYPE 0402LF
J 0
(4025 -1325);
DISPLAY 0.510638 (4025 -1325);
PAINT SKYBLUE (4025 -1325);
DISPLAY INVISIBLE (4025 -1325);
FORCEPROP 1 LAST PART_NUMBER CS03322FB03
J 0
(3725 -1075);
DISPLAY 0.510638 (3725 -1075);
PAINT WHITE (3725 -1075);
DISPLAY INVISIBLE (3725 -1075);
FORCEPROP 1 LAST TOLERANCE 1%
J 0
(3900 -1175);
DISPLAY 0.510638 (3900 -1175);
PAINT SKYBLUE (3900 -1175);
DISPLAY INVISIBLE (3900 -1175);
FORCEPROP 1 LAST LOCATION R713
J 2
(3725 -1225);
DISPLAY 0.702128 (3725 -1225);
PAINT YELLOW (3725 -1225);
FORCEPROP 1 LASTPIN (3675 -1175) $PN 1
J 0
(3690 -1165);
DISPLAY 0.808511 (3690 -1165);
PAINT WHITE (3690 -1165);
FORCEPROP 1 LASTPIN (3875 -1175) $PN 2
J 0
(3837 -1163);
DISPLAY 0.808511 (3837 -1163);
PAINT WHITE (3837 -1163);
FORCEPROP 0 LAST $SEC 1
J 0
(3875 -1125);
DISPLAY 0.680851 (3875 -1125);
PAINT MONO (3875 -1125);
DISPLAY INVISIBLE (3875 -1125);
FORCEPROP 0 LAST CDS_SEC 1
J 0
(3875 -1125);
DISPLAY 0.680851 (3875 -1125);
DISPLAY INVISIBLE (3875 -1125);
FORCEADD OFFPAGE..4
(4675 -1175);
FORCEPROP 2 LAST $XR2 27 
J 0
(4861 -1211);
DISPLAY 0.638298 (4861 -1211);
PAINT MONO (4861 -1211);
FORCEPROP 2 LAST $XR1 11 
J 0
(4951 -1175);
DISPLAY 0.638298 (4951 -1175);
PAINT MONO (4951 -1175);
FORCEPROP 2 LAST $XR0 10 
J 0
(4861 -1175);
DISPLAY 0.638298 (4861 -1175);
PAINT MONO (4861 -1175);
FORCEPROP 2 LAST CDS_LIB standard
J 0
(4675 -1175);
DISPLAY INVISIBLE (4675 -1175);
FORCEPROP 1 LAST OFFPAGE TRUE
J 0
(5000 -1300);
DISPLAY 0.872340 (5000 -1300);
PAINT GREEN (5000 -1300);
DISPLAY INVISIBLE (5000 -1300);
FORCEPROP 1 LAST COMMENT_BODY TRUE
J 0
(4650 -1275);
DISPLAY 0.872340 (4650 -1275);
PAINT PEACH (4650 -1275);
DISPLAY INVISIBLE (4650 -1275);
FORCEPROP 2 LAST PATH I229
J 0
(5025 -1125);
DISPLAY 1.021277 (5025 -1125);
DISPLAY INVISIBLE (5025 -1125);
FORCEADD Q_RES..2
(2825 -600);
FORCEPROP 1 LAST WATTAGE 1/16W
J 0
(2865 -625);
DISPLAY 0.510638 (2865 -625);
PAINT SKYBLUE (2865 -625);
FORCEPROP 1 LAST MATERIAL CHIP
J 0
(2865 -675);
DISPLAY 0.510638 (2865 -675);
PAINT SKYBLUE (2865 -675);
FORCEPROP 1 LAST VALUE 10K
J 0
(2870 -525);
DISPLAY 0.510638 (2870 -525);
PAINT SKYBLUE (2870 -525);
FORCEPROP 1 LAST TOLERANCE 1%
J 0
(2870 -575);
DISPLAY 0.510638 (2870 -575);
PAINT SKYBLUE (2870 -575);
FORCEPROP 1 LAST PART_NUMBER CS31002FB08
J 0
(2865 -725);
DISPLAY 0.510638 (2865 -725);
PAINT WHITE (2865 -725);
FORCEPROP 1 LAST PACK_TYPE 0402LF
J 0
(2865 -775);
DISPLAY 0.510638 (2865 -775);
PAINT SKYBLUE (2865 -775);
FORCEPROP 2 LAST CDS_LIB pure_quanta
J 0
(2825 -600);
DISPLAY INVISIBLE (2825 -600);
FORCEPROP 1 LAST PATH I230
J 0
(2875 -425);
DISPLAY 0.978723 (2875 -425);
PAINT WHITE (2875 -425);
DISPLAY INVISIBLE (2875 -425);
FORCEPROP 1 LAST LOCATION R716
J 0
(2870 -475);
DISPLAY 0.702128 (2870 -475);
PAINT YELLOW (2870 -475);
FORCEPROP 0 LAST $SEC 1
J 0
(2875 -425);
DISPLAY INVISIBLE (2875 -425);
FORCEPROP 0 LAST CDS_SEC 1
J 0
(2875 -425);
DISPLAY 0.680851 (2875 -425);
DISPLAY INVISIBLE (2875 -425);
FORCEPROP 1 LASTPIN (2825 -500) $PN 1
J 0
(2830 -538);
DISPLAY 0.808511 (2830 -538);
PAINT WHITE (2830 -538);
DISPLAY INVISIBLE (2830 -538);
FORCEPROP 1 LASTPIN (2825 -700) $PN 2
J 0
(2830 -690);
DISPLAY 0.808511 (2830 -690);
PAINT WHITE (2830 -690);
DISPLAY INVISIBLE (2830 -690);
FORCEADD UNIVERSAL_GND..1
(2825 -1650);
FORCEPROP 3 LASTPIN (2825 -1600) SIG_NAME GND\g
J 0
(2835 -1590);
DISPLAY 0.659574 (2835 -1590);
PAINT MONO (2835 -1590);
DISPLAY INVISIBLE (2835 -1590);
FORCEPROP 2 LAST CDS_LIB logical_power
J 0
(2825 -1650);
DISPLAY INVISIBLE (2825 -1650);
FORCEPROP 1 LAST HDL_POWER GND
J 1
(2850 -1725);
DISPLAY 0.702128 (2850 -1725);
PAINT GREEN (2850 -1725);
DISPLAY INVISIBLE (2850 -1725);
FORCEPROP 1 LAST PATH I232
J 0
(2900 -1650);
DISPLAY 0.872340 (2900 -1650);
PAINT AQUA (2900 -1650);
DISPLAY INVISIBLE (2900 -1650);
FORCEADD UNIVERSAL_GND..1
(3300 -1625);
FORCEPROP 3 LASTPIN (3300 -1575) SIG_NAME GND\g
J 0
(3310 -1565);
DISPLAY 0.659574 (3310 -1565);
PAINT MONO (3310 -1565);
DISPLAY INVISIBLE (3310 -1565);
FORCEPROP 2 LAST CDS_LIB logical_power
J 0
(3300 -1625);
DISPLAY INVISIBLE (3300 -1625);
FORCEPROP 1 LAST HDL_POWER GND
J 1
(3325 -1700);
DISPLAY 0.702128 (3325 -1700);
PAINT GREEN (3325 -1700);
DISPLAY INVISIBLE (3325 -1700);
FORCEPROP 1 LAST PATH I233
J 0
(3375 -1625);
DISPLAY 0.872340 (3375 -1625);
PAINT AQUA (3375 -1625);
DISPLAY INVISIBLE (3375 -1625);
FORCEADD Q_CAP..1
(3300 -1400);
FORCEPROP 1 LAST PACK_TYPE 0402
J 0
(3350 -1600);
DISPLAY 0.510638 (3350 -1600);
PAINT SKYBLUE (3350 -1600);
FORCEPROP 1 LAST MATERIAL EMPTY
J 0
(3350 -1500);
DISPLAY 0.510638 (3350 -1500);
PAINT RED (3350 -1500);
FORCEPROP 1 LAST TOLERANCE 10%
J 0
(3350 -1450);
DISPLAY 0.510638 (3350 -1450);
PAINT SKYBLUE (3350 -1450);
FORCEPROP 1 LAST VOLTAGE 16V
J 0
(3350 -1400);
DISPLAY 0.510638 (3350 -1400);
PAINT SKYBLUE (3350 -1400);
FORCEPROP 1 LAST PART_NUMBER TMP_QCH5103K9B00
J 0
(3350 -1550);
DISPLAY 0.510638 (3350 -1550);
PAINT WHITE (3350 -1550);
FORCEPROP 1 LAST VALUE 1UF
J 0
(3350 -1350);
DISPLAY 0.510638 (3350 -1350);
PAINT SKYBLUE (3350 -1350);
FORCEPROP 2 LAST CDS_LIB pure_quanta
J 0
(3300 -1400);
DISPLAY INVISIBLE (3300 -1400);
FORCEPROP 1 LAST PATH I234
J 0
(3350 -1250);
DISPLAY 0.978723 (3350 -1250);
PAINT WHITE (3350 -1250);
DISPLAY INVISIBLE (3350 -1250);
FORCEPROP 1 LAST LOCATION C273
J 0
(3350 -1300);
DISPLAY 0.702128 (3350 -1300);
PAINT YELLOW (3350 -1300);
FORCEPROP 1 LASTPIN (3300 -1300) $PN 1
J 0
(3310 -1320);
DISPLAY 0.808511 (3310 -1320);
PAINT WHITE (3310 -1320);
FORCEPROP 1 LASTPIN (3300 -1500) $PN 2
J 0
(3310 -1520);
DISPLAY 0.808511 (3310 -1520);
PAINT WHITE (3310 -1520);
FORCEPROP 0 LAST $SEC 1
J 0
(3350 -1250);
DISPLAY 0.680851 (3350 -1250);
PAINT MONO (3350 -1250);
DISPLAY INVISIBLE (3350 -1250);
FORCEPROP 0 LAST CDS_SEC 1
J 0
(3350 -1250);
DISPLAY 1.021277 (3350 -1250);
DISPLAY INVISIBLE (3350 -1250);
FORCEADD UNIVERSAL_POWER..1
(2825 -350);
FORCEPROP 3 LASTPIN (2825 -400) SIG_NAME P5V_AUX\g
J 0
(2835 -390);
DISPLAY 0.659574 (2835 -390);
PAINT MONO (2835 -390);
DISPLAY INVISIBLE (2835 -390);
FORCEPROP 1 LAST HDL_POWER P5V_AUX
J 1
(2825 -300);
DISPLAY 0.702128 (2825 -300);
PAINT GREEN (2825 -300);
FORCEPROP 1 LAST PATH I236
J 0
(2875 -325);
DISPLAY 0.872340 (2875 -325);
PAINT AQUA (2875 -325);
DISPLAY INVISIBLE (2875 -325);
FORCEPROP 2 LAST CDS_LIB logical_power
J 0
(2825 -350);
DISPLAY INVISIBLE (2825 -350);
FORCEADD Q_CAP..1
(2200 -1375);
FORCEPROP 1 LAST PART_NUMBER TMP_QCH5103K9B00
J 0
(2250 -1525);
DISPLAY 0.510638 (2250 -1525);
PAINT WHITE (2250 -1525);
FORCEPROP 1 LAST VOLTAGE 16V
J 0
(2250 -1375);
DISPLAY 0.510638 (2250 -1375);
PAINT SKYBLUE (2250 -1375);
FORCEPROP 1 LAST VALUE 1UF
J 0
(2250 -1325);
DISPLAY 0.510638 (2250 -1325);
PAINT SKYBLUE (2250 -1325);
FORCEPROP 1 LAST TOLERANCE 10%
J 0
(2250 -1425);
DISPLAY 0.510638 (2250 -1425);
PAINT SKYBLUE (2250 -1425);
FORCEPROP 1 LAST PACK_TYPE 0402
J 0
(2250 -1575);
DISPLAY 0.510638 (2250 -1575);
PAINT SKYBLUE (2250 -1575);
FORCEPROP 1 LAST MATERIAL EMPTY
J 0
(2250 -1475);
DISPLAY 0.510638 (2250 -1475);
PAINT RED (2250 -1475);
FORCEPROP 2 LAST CDS_LIB pure_quanta
J 0
(2200 -1375);
DISPLAY INVISIBLE (2200 -1375);
FORCEPROP 1 LAST PATH I239
J 0
(2250 -1225);
DISPLAY 0.978723 (2250 -1225);
PAINT WHITE (2250 -1225);
DISPLAY INVISIBLE (2250 -1225);
FORCEPROP 1 LAST LOCATION C270
J 0
(2250 -1275);
DISPLAY 0.702128 (2250 -1275);
PAINT YELLOW (2250 -1275);
FORCEPROP 1 LASTPIN (2200 -1275) $PN 1
J 0
(2210 -1295);
DISPLAY 0.808511 (2210 -1295);
PAINT WHITE (2210 -1295);
FORCEPROP 1 LASTPIN (2200 -1475) $PN 2
J 0
(2210 -1495);
DISPLAY 0.808511 (2210 -1495);
PAINT WHITE (2210 -1495);
FORCEPROP 0 LAST $SEC 1
J 0
(2250 -1225);
DISPLAY 0.680851 (2250 -1225);
PAINT MONO (2250 -1225);
DISPLAY INVISIBLE (2250 -1225);
FORCEPROP 0 LAST CDS_SEC 1
J 0
(2250 -1225);
DISPLAY 1.021277 (2250 -1225);
DISPLAY INVISIBLE (2250 -1225);
FORCEADD UNIVERSAL_GND..1
(2200 -1600);
FORCEPROP 3 LASTPIN (2200 -1550) SIG_NAME GND\g
J 0
(2210 -1540);
DISPLAY 0.659574 (2210 -1540);
PAINT MONO (2210 -1540);
DISPLAY INVISIBLE (2210 -1540);
FORCEPROP 2 LAST CDS_LIB logical_power
J 0
(2200 -1600);
DISPLAY INVISIBLE (2200 -1600);
FORCEPROP 1 LAST HDL_POWER GND
J 1
(2225 -1675);
DISPLAY 0.702128 (2225 -1675);
PAINT GREEN (2225 -1675);
DISPLAY INVISIBLE (2225 -1675);
FORCEPROP 1 LAST PATH I240
J 0
(2275 -1600);
DISPLAY 0.872340 (2275 -1600);
PAINT AQUA (2275 -1600);
DISPLAY INVISIBLE (2275 -1600);
FORCEADD OFFPAGE..2
(50 -1050);
FORCEPROP 2 LAST $XR0 16 
J 0
(239 -1050);
DISPLAY 0.638298 (239 -1050);
PAINT MONO (239 -1050);
FORCEPROP 2 LAST CDS_LIB standard
J 0
(50 -1050);
DISPLAY INVISIBLE (50 -1050);
FORCEPROP 1 LAST OFFPAGE TRUE
J 0
(375 -1175);
DISPLAY 0.872340 (375 -1175);
PAINT GREEN (375 -1175);
DISPLAY INVISIBLE (375 -1175);
FORCEPROP 1 LAST COMMENT_BODY TRUE
J 0
(5 -1145);
DISPLAY 0.872340 (5 -1145);
PAINT PEACH (5 -1145);
DISPLAY INVISIBLE (5 -1145);
FORCEPROP 2 LAST PATH I248
J 0
(225 -975);
DISPLAY 1.021277 (225 -975);
DISPLAY INVISIBLE (225 -975);
FORCEADD OFFPAGE..2
(-2275 -1050);
FORCEPROP 2 LAST $XR0 16 
J 0
(-2086 -1050);
DISPLAY 0.638298 (-2086 -1050);
PAINT MONO (-2086 -1050);
FORCEPROP 2 LAST CDS_LIB standard
J 0
(-2275 -1050);
DISPLAY INVISIBLE (-2275 -1050);
FORCEPROP 1 LAST OFFPAGE TRUE
J 0
(-1950 -1175);
DISPLAY 0.872340 (-1950 -1175);
PAINT GREEN (-1950 -1175);
DISPLAY INVISIBLE (-1950 -1175);
FORCEPROP 1 LAST COMMENT_BODY TRUE
J 0
(-2320 -1145);
DISPLAY 0.872340 (-2320 -1145);
PAINT PEACH (-2320 -1145);
DISPLAY INVISIBLE (-2320 -1145);
FORCEPROP 2 LAST PATH I249
J 0
(-2100 -975);
DISPLAY 1.021277 (-2100 -975);
DISPLAY INVISIBLE (-2100 -975);
FORCEADD Q_CAP..1
(-250 -1225);
FORCEPROP 1 LAST PART_NUMBER CH4104K1B00
J 0
(-200 -1425);
DISPLAY 0.510638 (-200 -1425);
PAINT WHITE (-200 -1425);
FORCEPROP 1 LAST VOLTAGE 25V
J 0
(-200 -1225);
DISPLAY 0.510638 (-200 -1225);
PAINT SKYBLUE (-200 -1225);
FORCEPROP 1 LAST MATERIAL X7R
J 0
(-200 -1325);
DISPLAY 0.510638 (-200 -1325);
PAINT SKYBLUE (-200 -1325);
FORCEPROP 1 LAST TOLERANCE 10%
J 0
(-200 -1275);
DISPLAY 0.510638 (-200 -1275);
PAINT SKYBLUE (-200 -1275);
FORCEPROP 1 LAST VALUE 0.1UF
J 0
(-200 -1175);
DISPLAY 0.510638 (-200 -1175);
PAINT SKYBLUE (-200 -1175);
FORCEPROP 1 LAST PACK_TYPE 0402
J 0
(-200 -1375);
DISPLAY 0.510638 (-200 -1375);
PAINT SKYBLUE (-200 -1375);
FORCEPROP 2 LAST CDS_LIB pure_quanta
J 0
(-250 -1225);
DISPLAY INVISIBLE (-250 -1225);
FORCEPROP 1 LAST PATH I250
J 0
(-200 -1075);
DISPLAY 0.978723 (-200 -1075);
PAINT WHITE (-200 -1075);
DISPLAY INVISIBLE (-200 -1075);
FORCEPROP 1 LAST LOCATION C284
J 0
(-200 -1125);
DISPLAY 0.702128 (-200 -1125);
PAINT YELLOW (-200 -1125);
FORCEPROP 1 LASTPIN (-250 -1125) $PN 1
J 0
(-240 -1145);
DISPLAY 0.808511 (-240 -1145);
PAINT WHITE (-240 -1145);
FORCEPROP 1 LASTPIN (-250 -1325) $PN 2
J 0
(-240 -1345);
DISPLAY 0.808511 (-240 -1345);
PAINT WHITE (-240 -1345);
FORCEPROP 2 LAST $SEC 1
J 0
(-200 -1025);
DISPLAY 0.680851 (-200 -1025);
PAINT MONO (-200 -1025);
DISPLAY INVISIBLE (-200 -1025);
FORCEPROP 0 LAST CDS_SEC 1
J 0
(-200 -1025);
DISPLAY 0.680851 (-200 -1025);
PAINT MONO (-200 -1025);
DISPLAY INVISIBLE (-200 -1025);
FORCEADD UNIVERSAL_GND..1
(-425 -1525);
FORCEPROP 3 LASTPIN (-425 -1475) SIG_NAME GND\g
J 0
(-415 -1465);
DISPLAY 0.659574 (-415 -1465);
PAINT MONO (-415 -1465);
DISPLAY INVISIBLE (-415 -1465);
FORCEPROP 2 LAST CDS_LIB logical_power
J 0
(-425 -1525);
DISPLAY INVISIBLE (-425 -1525);
FORCEPROP 1 LAST HDL_POWER GND
J 1
(-400 -1600);
DISPLAY 0.702128 (-400 -1600);
PAINT GREEN (-400 -1600);
DISPLAY INVISIBLE (-400 -1600);
FORCEPROP 1 LAST PATH I251
J 0
(-350 -1525);
DISPLAY 0.872340 (-350 -1525);
PAINT AQUA (-350 -1525);
DISPLAY INVISIBLE (-350 -1525);
FORCEADD Q_CAP..1
(-600 -1225);
FORCEPROP 1 LAST VOLTAGE 25V
J 0
(-550 -1225);
DISPLAY 0.510638 (-550 -1225);
PAINT SKYBLUE (-550 -1225);
FORCEPROP 1 LAST VALUE 1UF
J 0
(-550 -1175);
DISPLAY 0.510638 (-550 -1175);
PAINT SKYBLUE (-550 -1175);
FORCEPROP 1 LAST PART_NUMBER CH5104KEB02
J 0
(-550 -1425);
DISPLAY 0.510638 (-550 -1425);
PAINT WHITE (-550 -1425);
FORCEPROP 1 LAST MATERIAL X6S
J 0
(-550 -1325);
DISPLAY 0.510638 (-550 -1325);
PAINT SKYBLUE (-550 -1325);
FORCEPROP 1 LAST TOLERANCE 10%
J 0
(-550 -1275);
DISPLAY 0.510638 (-550 -1275);
PAINT SKYBLUE (-550 -1275);
FORCEPROP 1 LAST PACK_TYPE C0402
J 0
(-550 -1375);
DISPLAY 0.510638 (-550 -1375);
PAINT SKYBLUE (-550 -1375);
FORCEPROP 2 LAST CDS_LIB pure_quanta
J 0
(-600 -1225);
DISPLAY INVISIBLE (-600 -1225);
FORCEPROP 1 LAST PATH I252
J 0
(-550 -1075);
DISPLAY 0.978723 (-550 -1075);
PAINT WHITE (-550 -1075);
DISPLAY INVISIBLE (-550 -1075);
FORCEPROP 1 LAST LOCATION C282
J 0
(-550 -1125);
DISPLAY 0.702128 (-550 -1125);
PAINT YELLOW (-550 -1125);
FORCEPROP 1 LASTPIN (-600 -1125) $PN 1
J 0
(-590 -1145);
DISPLAY 0.808511 (-590 -1145);
PAINT WHITE (-590 -1145);
FORCEPROP 1 LASTPIN (-600 -1325) $PN 2
J 0
(-590 -1345);
DISPLAY 0.808511 (-590 -1345);
PAINT WHITE (-590 -1345);
FORCEPROP 2 LAST $SEC 1
J 0
(-550 -1025);
DISPLAY 0.680851 (-550 -1025);
PAINT MONO (-550 -1025);
DISPLAY INVISIBLE (-550 -1025);
FORCEPROP 0 LAST CDS_SEC 1
J 0
(-550 -1025);
DISPLAY 0.680851 (-550 -1025);
PAINT MONO (-550 -1025);
DISPLAY INVISIBLE (-550 -1025);
FORCEADD Q_CAP..1
(-2900 -1225);
FORCEPROP 1 LAST PART_NUMBER CH5104KEB02
J 0
(-2850 -1425);
DISPLAY 0.510638 (-2850 -1425);
PAINT WHITE (-2850 -1425);
FORCEPROP 1 LAST VOLTAGE 25V
J 0
(-2850 -1225);
DISPLAY 0.510638 (-2850 -1225);
PAINT SKYBLUE (-2850 -1225);
FORCEPROP 1 LAST VALUE 1UF
J 0
(-2850 -1175);
DISPLAY 0.510638 (-2850 -1175);
PAINT SKYBLUE (-2850 -1175);
FORCEPROP 1 LAST MATERIAL X6S
J 0
(-2850 -1325);
DISPLAY 0.510638 (-2850 -1325);
PAINT SKYBLUE (-2850 -1325);
FORCEPROP 1 LAST TOLERANCE 10%
J 0
(-2850 -1275);
DISPLAY 0.510638 (-2850 -1275);
PAINT SKYBLUE (-2850 -1275);
FORCEPROP 1 LAST PACK_TYPE C0402
J 0
(-2850 -1375);
DISPLAY 0.510638 (-2850 -1375);
PAINT SKYBLUE (-2850 -1375);
FORCEPROP 2 LAST CDS_LIB pure_quanta
J 0
(-2900 -1225);
DISPLAY INVISIBLE (-2900 -1225);
FORCEPROP 1 LAST PATH I253
J 0
(-2850 -1075);
DISPLAY 0.978723 (-2850 -1075);
PAINT WHITE (-2850 -1075);
DISPLAY INVISIBLE (-2850 -1075);
FORCEPROP 1 LAST LOCATION C277
J 0
(-2850 -1125);
DISPLAY 0.702128 (-2850 -1125);
PAINT YELLOW (-2850 -1125);
FORCEPROP 1 LASTPIN (-2900 -1125) $PN 1
J 0
(-2890 -1145);
DISPLAY 0.808511 (-2890 -1145);
PAINT WHITE (-2890 -1145);
FORCEPROP 1 LASTPIN (-2900 -1325) $PN 2
J 0
(-2890 -1345);
DISPLAY 0.808511 (-2890 -1345);
PAINT WHITE (-2890 -1345);
FORCEPROP 2 LAST $SEC 1
J 0
(-2850 -1025);
DISPLAY 0.680851 (-2850 -1025);
PAINT MONO (-2850 -1025);
DISPLAY INVISIBLE (-2850 -1025);
FORCEPROP 0 LAST CDS_SEC 1
J 0
(-2850 -1025);
DISPLAY 0.680851 (-2850 -1025);
PAINT MONO (-2850 -1025);
DISPLAY INVISIBLE (-2850 -1025);
FORCEADD UNIVERSAL_GND..1
(-2725 -1525);
FORCEPROP 3 LASTPIN (-2725 -1475) SIG_NAME GND\g
J 0
(-2715 -1465);
DISPLAY 0.659574 (-2715 -1465);
PAINT MONO (-2715 -1465);
DISPLAY INVISIBLE (-2715 -1465);
FORCEPROP 2 LAST CDS_LIB logical_power
J 0
(-2725 -1525);
DISPLAY INVISIBLE (-2725 -1525);
FORCEPROP 1 LAST HDL_POWER GND
J 1
(-2700 -1600);
DISPLAY 0.702128 (-2700 -1600);
PAINT GREEN (-2700 -1600);
DISPLAY INVISIBLE (-2700 -1600);
FORCEPROP 1 LAST PATH I254
J 0
(-2650 -1525);
DISPLAY 0.872340 (-2650 -1525);
PAINT AQUA (-2650 -1525);
DISPLAY INVISIBLE (-2650 -1525);
FORCEADD Q_CAP..1
(-2550 -1225);
FORCEPROP 1 LAST VOLTAGE 25V
J 0
(-2500 -1225);
DISPLAY 0.510638 (-2500 -1225);
PAINT SKYBLUE (-2500 -1225);
FORCEPROP 1 LAST PART_NUMBER CH4104K1B00
J 0
(-2500 -1425);
DISPLAY 0.510638 (-2500 -1425);
PAINT WHITE (-2500 -1425);
FORCEPROP 1 LAST MATERIAL X7R
J 0
(-2500 -1325);
DISPLAY 0.510638 (-2500 -1325);
PAINT SKYBLUE (-2500 -1325);
FORCEPROP 1 LAST TOLERANCE 10%
J 0
(-2500 -1275);
DISPLAY 0.510638 (-2500 -1275);
PAINT SKYBLUE (-2500 -1275);
FORCEPROP 1 LAST VALUE 0.1UF
J 0
(-2500 -1175);
DISPLAY 0.510638 (-2500 -1175);
PAINT SKYBLUE (-2500 -1175);
FORCEPROP 1 LAST PACK_TYPE 0402
J 0
(-2500 -1375);
DISPLAY 0.510638 (-2500 -1375);
PAINT SKYBLUE (-2500 -1375);
FORCEPROP 2 LAST CDS_LIB pure_quanta
J 0
(-2550 -1225);
DISPLAY INVISIBLE (-2550 -1225);
FORCEPROP 1 LAST PATH I255
J 0
(-2500 -1075);
DISPLAY 0.978723 (-2500 -1075);
PAINT WHITE (-2500 -1075);
DISPLAY INVISIBLE (-2500 -1075);
FORCEPROP 1 LAST LOCATION C279
J 0
(-2500 -1125);
DISPLAY 0.702128 (-2500 -1125);
PAINT YELLOW (-2500 -1125);
FORCEPROP 1 LASTPIN (-2550 -1125) $PN 1
J 0
(-2540 -1145);
DISPLAY 0.808511 (-2540 -1145);
PAINT WHITE (-2540 -1145);
FORCEPROP 1 LASTPIN (-2550 -1325) $PN 2
J 0
(-2540 -1345);
DISPLAY 0.808511 (-2540 -1345);
PAINT WHITE (-2540 -1345);
FORCEPROP 2 LAST $SEC 1
J 0
(-2500 -1025);
DISPLAY 0.680851 (-2500 -1025);
PAINT MONO (-2500 -1025);
DISPLAY INVISIBLE (-2500 -1025);
FORCEPROP 0 LAST CDS_SEC 1
J 0
(-2500 -1025);
DISPLAY 0.680851 (-2500 -1025);
PAINT MONO (-2500 -1025);
DISPLAY INVISIBLE (-2500 -1025);
FORCEADD Q_RES..1
(-1125 -1050);
FORCEPROP 1 LAST VALUE 0
J 2
(-925 -1050);
DISPLAY 0.510638 (-925 -1050);
PAINT SKYBLUE (-925 -1050);
FORCEPROP 1 LAST TOLERANCE 5%
J 0
(-875 -1225);
DISPLAY 0.510638 (-875 -1225);
PAINT SKYBLUE (-875 -1225);
FORCEPROP 1 LAST MATERIAL EMPTY
J 0
(-850 -1050);
DISPLAY 0.510638 (-850 -1050);
PAINT RED (-850 -1050);
FORCEPROP 1 LAST WATTAGE 1/16W
J 2
(-900 -1225);
DISPLAY 0.510638 (-900 -1225);
PAINT SKYBLUE (-900 -1225);
FORCEPROP 1 LAST PACK_TYPE 0402LF
J 0
(-1000 -1175);
DISPLAY 0.510638 (-1000 -1175);
PAINT SKYBLUE (-1000 -1175);
FORCEPROP 1 LAST PART_NUMBER CS00002JB13
J 0
(-1000 -1125);
DISPLAY 0.510638 (-1000 -1125);
PAINT WHITE (-1000 -1125);
FORCEPROP 2 LAST CDS_LIB pure_quanta
J 0
(-1125 -1050);
DISPLAY INVISIBLE (-1125 -1050);
FORCEPROP 1 LAST PATH I256
J 0
(-1175 -900);
DISPLAY 0.978723 (-1175 -900);
PAINT WHITE (-1175 -900);
DISPLAY INVISIBLE (-1175 -900);
FORCEPROP 1 LAST LOCATION R780
J 0
(-1450 -1050);
DISPLAY 0.702128 (-1450 -1050);
PAINT YELLOW (-1450 -1050);
FORCEPROP 1 LASTPIN (-1225 -1050) $PN 1
J 0
(-1213 -1038);
DISPLAY 0.808511 (-1213 -1038);
PAINT WHITE (-1213 -1038);
FORCEPROP 1 LASTPIN (-1025 -1050) $PN 2
J 0
(-1063 -1038);
DISPLAY 0.808511 (-1063 -1038);
PAINT WHITE (-1063 -1038);
FORCEPROP 0 LAST $SEC 1
J 0
(-850 -1000);
DISPLAY 0.680851 (-850 -1000);
PAINT MONO (-850 -1000);
DISPLAY INVISIBLE (-850 -1000);
FORCEPROP 0 LAST CDS_SEC 1
J 0
(-850 -1000);
DISPLAY 0.680851 (-850 -1000);
DISPLAY INVISIBLE (-850 -1000);
FORCEADD Q_RES..1
(-3425 -1050);
FORCEPROP 1 LAST VALUE 0
J 2
(-3225 -1050);
DISPLAY 0.510638 (-3225 -1050);
PAINT SKYBLUE (-3225 -1050);
FORCEPROP 1 LAST TOLERANCE 5%
J 0
(-3175 -1225);
DISPLAY 0.510638 (-3175 -1225);
PAINT SKYBLUE (-3175 -1225);
FORCEPROP 1 LAST WATTAGE 1/16W
J 2
(-3200 -1225);
DISPLAY 0.510638 (-3200 -1225);
PAINT SKYBLUE (-3200 -1225);
FORCEPROP 1 LAST MATERIAL CHIP
J 0
(-3150 -1050);
DISPLAY 0.510638 (-3150 -1050);
PAINT SKYBLUE (-3150 -1050);
FORCEPROP 1 LAST PACK_TYPE 0402LF
J 0
(-3300 -1175);
DISPLAY 0.510638 (-3300 -1175);
PAINT SKYBLUE (-3300 -1175);
FORCEPROP 1 LAST PART_NUMBER CS00002JB13
J 0
(-3300 -1125);
DISPLAY 0.510638 (-3300 -1125);
PAINT WHITE (-3300 -1125);
FORCEPROP 2 LAST CDS_LIB pure_quanta
J 0
(-3425 -1050);
DISPLAY INVISIBLE (-3425 -1050);
FORCEPROP 1 LAST PATH I259
J 0
(-3475 -900);
DISPLAY 0.978723 (-3475 -900);
PAINT WHITE (-3475 -900);
DISPLAY INVISIBLE (-3475 -900);
FORCEPROP 1 LAST LOCATION R779
J 0
(-3750 -1050);
DISPLAY 0.702128 (-3750 -1050);
PAINT YELLOW (-3750 -1050);
FORCEPROP 1 LASTPIN (-3525 -1050) $PN 1
J 0
(-3513 -1038);
DISPLAY 0.808511 (-3513 -1038);
PAINT WHITE (-3513 -1038);
FORCEPROP 1 LASTPIN (-3325 -1050) $PN 2
J 0
(-3363 -1038);
DISPLAY 0.808511 (-3363 -1038);
PAINT WHITE (-3363 -1038);
FORCEPROP 0 LAST $SEC 1
J 0
(-3150 -1000);
DISPLAY 0.680851 (-3150 -1000);
PAINT MONO (-3150 -1000);
DISPLAY INVISIBLE (-3150 -1000);
FORCEPROP 0 LAST CDS_SEC 1
J 0
(-3150 -1000);
DISPLAY 0.680851 (-3150 -1000);
DISPLAY INVISIBLE (-3150 -1000);
FORCEADD Q_RES..1
(-1225 -1325);
FORCEPROP 1 LAST VALUE 0
J 2
(-1025 -1325);
DISPLAY 0.510638 (-1025 -1325);
PAINT SKYBLUE (-1025 -1325);
FORCEPROP 1 LAST TOLERANCE 5%
J 0
(-975 -1500);
DISPLAY 0.510638 (-975 -1500);
PAINT SKYBLUE (-975 -1500);
FORCEPROP 1 LAST WATTAGE 1/16W
J 2
(-1000 -1500);
DISPLAY 0.510638 (-1000 -1500);
PAINT SKYBLUE (-1000 -1500);
FORCEPROP 1 LAST MATERIAL CHIP
J 0
(-950 -1325);
DISPLAY 0.510638 (-950 -1325);
PAINT SKYBLUE (-950 -1325);
FORCEPROP 1 LAST PACK_TYPE 0402LF
J 0
(-1100 -1450);
DISPLAY 0.510638 (-1100 -1450);
PAINT SKYBLUE (-1100 -1450);
FORCEPROP 1 LAST PART_NUMBER CS00002JB13
J 0
(-1100 -1400);
DISPLAY 0.510638 (-1100 -1400);
PAINT WHITE (-1100 -1400);
FORCEPROP 2 LAST CDS_LIB pure_quanta
J 0
(-1225 -1325);
DISPLAY INVISIBLE (-1225 -1325);
FORCEPROP 1 LAST PATH I260
J 0
(-1275 -1175);
DISPLAY 0.978723 (-1275 -1175);
PAINT WHITE (-1275 -1175);
DISPLAY INVISIBLE (-1275 -1175);
FORCEPROP 1 LAST LOCATION R783
J 0
(-1525 -1325);
DISPLAY 0.702128 (-1525 -1325);
PAINT YELLOW (-1525 -1325);
FORCEPROP 0 LAST $SEC 1
J 0
(-1525 -1275);
DISPLAY 0.680851 (-1525 -1275);
PAINT MONO (-1525 -1275);
DISPLAY INVISIBLE (-1525 -1275);
FORCEPROP 0 LAST CDS_SEC 1
J 0
(-1525 -1275);
DISPLAY 1.021277 (-1525 -1275);
DISPLAY INVISIBLE (-1525 -1275);
FORCEPROP 1 LASTPIN (-1325 -1325) $PN 1
J 0
(-1313 -1313);
DISPLAY 0.808511 (-1313 -1313);
PAINT WHITE (-1313 -1313);
DISPLAY INVISIBLE (-1313 -1313);
FORCEPROP 1 LASTPIN (-1125 -1325) $PN 2
J 0
(-1163 -1313);
DISPLAY 0.808511 (-1163 -1313);
PAINT WHITE (-1163 -1313);
DISPLAY INVISIBLE (-1163 -1313);
FORCEADD UNIVERSAL_POWER..1
(-1650 -1175);
FORCEPROP 3 LASTPIN (-1650 -1225) SIG_NAME P1V8_AUX\g
J 0
(-1640 -1215);
DISPLAY 0.659574 (-1640 -1215);
PAINT MONO (-1640 -1215);
DISPLAY INVISIBLE (-1640 -1215);
FORCEPROP 1 LAST HDL_POWER P1V8_AUX
J 1
(-1650 -1125);
DISPLAY 0.702128 (-1650 -1125);
PAINT GREEN (-1650 -1125);
FORCEPROP 2 LAST CDS_LIB logical_power
J 0
(-1650 -1175);
DISPLAY INVISIBLE (-1650 -1175);
FORCEPROP 1 LAST PATH I261
J 0
(-1600 -1150);
DISPLAY 0.872340 (-1600 -1150);
PAINT AQUA (-1600 -1150);
DISPLAY INVISIBLE (-1600 -1150);
FORCEADD UNIVERSAL_POWER..1
(-3950 -1175);
FORCEPROP 3 LASTPIN (-3950 -1225) SIG_NAME P1V8_AUX\g
J 0
(-3940 -1215);
DISPLAY 0.659574 (-3940 -1215);
PAINT MONO (-3940 -1215);
DISPLAY INVISIBLE (-3940 -1215);
FORCEPROP 1 LAST HDL_POWER P1V8_AUX
J 1
(-3950 -1125);
DISPLAY 0.702128 (-3950 -1125);
PAINT GREEN (-3950 -1125);
FORCEPROP 2 LAST CDS_LIB logical_power
J 0
(-3950 -1175);
DISPLAY INVISIBLE (-3950 -1175);
FORCEPROP 1 LAST PATH I262
J 0
(-3900 -1150);
DISPLAY 0.872340 (-3900 -1150);
PAINT AQUA (-3900 -1150);
DISPLAY INVISIBLE (-3900 -1150);
FORCEADD Q_RES..1
(-3525 -1325);
FORCEPROP 1 LAST VALUE 0
J 2
(-3325 -1325);
DISPLAY 0.510638 (-3325 -1325);
PAINT SKYBLUE (-3325 -1325);
FORCEPROP 1 LAST TOLERANCE 5%
J 0
(-3275 -1500);
DISPLAY 0.510638 (-3275 -1500);
PAINT SKYBLUE (-3275 -1500);
FORCEPROP 1 LAST MATERIAL EMPTY
J 0
(-3250 -1325);
DISPLAY 0.510638 (-3250 -1325);
PAINT RED (-3250 -1325);
FORCEPROP 1 LAST WATTAGE 1/16W
J 2
(-3300 -1500);
DISPLAY 0.510638 (-3300 -1500);
PAINT SKYBLUE (-3300 -1500);
FORCEPROP 1 LAST PACK_TYPE 0402LF
J 0
(-3400 -1450);
DISPLAY 0.510638 (-3400 -1450);
PAINT SKYBLUE (-3400 -1450);
FORCEPROP 1 LAST PART_NUMBER CS00002JB13
J 0
(-3400 -1400);
DISPLAY 0.510638 (-3400 -1400);
PAINT WHITE (-3400 -1400);
FORCEPROP 2 LAST CDS_LIB pure_quanta
J 0
(-3525 -1325);
DISPLAY INVISIBLE (-3525 -1325);
FORCEPROP 1 LAST PATH I263
J 0
(-3575 -1175);
DISPLAY 0.978723 (-3575 -1175);
PAINT WHITE (-3575 -1175);
DISPLAY INVISIBLE (-3575 -1175);
FORCEPROP 1 LAST LOCATION R781
J 0
(-3800 -1325);
DISPLAY 0.702128 (-3800 -1325);
PAINT YELLOW (-3800 -1325);
FORCEPROP 0 LAST $SEC 1
J 0
(-3800 -1275);
DISPLAY 0.680851 (-3800 -1275);
PAINT MONO (-3800 -1275);
DISPLAY INVISIBLE (-3800 -1275);
FORCEPROP 0 LAST CDS_SEC 1
J 0
(-3800 -1275);
DISPLAY 1.021277 (-3800 -1275);
DISPLAY INVISIBLE (-3800 -1275);
FORCEPROP 1 LASTPIN (-3625 -1325) $PN 1
J 0
(-3613 -1313);
DISPLAY 0.808511 (-3613 -1313);
PAINT WHITE (-3613 -1313);
DISPLAY INVISIBLE (-3613 -1313);
FORCEPROP 1 LASTPIN (-3425 -1325) $PN 2
J 0
(-3463 -1313);
DISPLAY 0.808511 (-3463 -1313);
PAINT WHITE (-3463 -1313);
DISPLAY INVISIBLE (-3463 -1313);
FORCEADD Q_RES..1
(-3525 -1600);
FORCEPROP 1 LAST VALUE 0
J 2
(-3325 -1600);
DISPLAY 0.510638 (-3325 -1600);
PAINT SKYBLUE (-3325 -1600);
FORCEPROP 1 LAST TOLERANCE 5%
J 0
(-3275 -1775);
DISPLAY 0.510638 (-3275 -1775);
PAINT SKYBLUE (-3275 -1775);
FORCEPROP 1 LAST MATERIAL EMPTY
J 0
(-3250 -1600);
DISPLAY 0.510638 (-3250 -1600);
PAINT RED (-3250 -1600);
FORCEPROP 1 LAST PACK_TYPE 0402LF
J 0
(-3400 -1725);
DISPLAY 0.510638 (-3400 -1725);
PAINT SKYBLUE (-3400 -1725);
FORCEPROP 1 LAST PART_NUMBER CS00002JB13
J 0
(-3400 -1675);
DISPLAY 0.510638 (-3400 -1675);
PAINT WHITE (-3400 -1675);
FORCEPROP 1 LAST WATTAGE 1/16W
J 2
(-3300 -1775);
DISPLAY 0.510638 (-3300 -1775);
PAINT SKYBLUE (-3300 -1775);
FORCEPROP 2 LAST CDS_LIB pure_quanta
J 0
(-3525 -1600);
DISPLAY INVISIBLE (-3525 -1600);
FORCEPROP 1 LAST PATH I264
J 0
(-3575 -1450);
DISPLAY 0.978723 (-3575 -1450);
PAINT WHITE (-3575 -1450);
DISPLAY INVISIBLE (-3575 -1450);
FORCEPROP 1 LAST LOCATION R782
J 0
(-3800 -1600);
DISPLAY 0.702128 (-3800 -1600);
PAINT YELLOW (-3800 -1600);
FORCEPROP 0 LAST $SEC 1
J 0
(-3800 -1550);
DISPLAY 0.680851 (-3800 -1550);
PAINT MONO (-3800 -1550);
DISPLAY INVISIBLE (-3800 -1550);
FORCEPROP 0 LAST CDS_SEC 1
J 0
(-3800 -1550);
DISPLAY 1.021277 (-3800 -1550);
DISPLAY INVISIBLE (-3800 -1550);
FORCEPROP 1 LASTPIN (-3625 -1600) $PN 1
J 0
(-3613 -1588);
DISPLAY 0.808511 (-3613 -1588);
PAINT WHITE (-3613 -1588);
DISPLAY INVISIBLE (-3613 -1588);
FORCEPROP 1 LASTPIN (-3425 -1600) $PN 2
J 0
(-3463 -1588);
DISPLAY 0.808511 (-3463 -1588);
PAINT WHITE (-3463 -1588);
DISPLAY INVISIBLE (-3463 -1588);
FORCEADD Q_RES..1
(-1225 -1600);
FORCEPROP 1 LAST PACK_TYPE 0402LF
J 0
(-1100 -1725);
DISPLAY 0.510638 (-1100 -1725);
PAINT SKYBLUE (-1100 -1725);
FORCEPROP 1 LAST WATTAGE 1/16W
J 2
(-1000 -1775);
DISPLAY 0.510638 (-1000 -1775);
PAINT SKYBLUE (-1000 -1775);
FORCEPROP 1 LAST TOLERANCE 5%
J 0
(-975 -1775);
DISPLAY 0.510638 (-975 -1775);
PAINT SKYBLUE (-975 -1775);
FORCEPROP 1 LAST VALUE 0
J 2
(-1025 -1600);
DISPLAY 0.510638 (-1025 -1600);
PAINT SKYBLUE (-1025 -1600);
FORCEPROP 1 LAST MATERIAL EMPTY
J 0
(-950 -1600);
DISPLAY 0.510638 (-950 -1600);
PAINT RED (-950 -1600);
FORCEPROP 1 LAST PART_NUMBER CS00002JB13
J 0
(-1100 -1675);
DISPLAY 0.510638 (-1100 -1675);
PAINT WHITE (-1100 -1675);
FORCEPROP 2 LAST CDS_LIB pure_quanta
J 0
(-1225 -1600);
DISPLAY INVISIBLE (-1225 -1600);
FORCEPROP 1 LAST PATH I267
J 0
(-1275 -1450);
DISPLAY 0.978723 (-1275 -1450);
PAINT WHITE (-1275 -1450);
DISPLAY INVISIBLE (-1275 -1450);
FORCEPROP 1 LAST LOCATION R784
J 0
(-1525 -1600);
DISPLAY 0.702128 (-1525 -1600);
PAINT YELLOW (-1525 -1600);
FORCEPROP 0 LAST $SEC 1
J 0
(-1525 -1550);
DISPLAY 0.680851 (-1525 -1550);
PAINT MONO (-1525 -1550);
DISPLAY INVISIBLE (-1525 -1550);
FORCEPROP 0 LAST CDS_SEC 1
J 0
(-1525 -1550);
DISPLAY 1.021277 (-1525 -1550);
DISPLAY INVISIBLE (-1525 -1550);
FORCEPROP 1 LASTPIN (-1325 -1600) $PN 1
J 0
(-1313 -1588);
DISPLAY 0.808511 (-1313 -1588);
PAINT WHITE (-1313 -1588);
DISPLAY INVISIBLE (-1313 -1588);
FORCEPROP 1 LASTPIN (-1125 -1600) $PN 2
J 0
(-1163 -1588);
DISPLAY 0.808511 (-1163 -1588);
PAINT WHITE (-1163 -1588);
DISPLAY INVISIBLE (-1163 -1588);
FORCEADD VCCAUX15..1
(-1550 -900);
FORCEPROP 3 LASTPIN (-1550 -950) SIG_NAME P2V5_AUX\g
J 0
(-1540 -940);
DISPLAY 0.659574 (-1540 -940);
PAINT MONO (-1540 -940);
DISPLAY INVISIBLE (-1540 -940);
FORCEPROP 1 LAST HDL_POWER P2V5_AUX
J 1
(-1550 -850);
DISPLAY 0.702128 (-1550 -850);
PAINT GREEN (-1550 -850);
FORCEPROP 2 LAST CDS_LIB logical_power
J 0
(-1550 -900);
DISPLAY INVISIBLE (-1550 -900);
FORCEPROP 1 LAST PATH I268
J 0
(-1500 -875);
DISPLAY 0.872340 (-1500 -875);
PAINT AQUA (-1500 -875);
DISPLAY INVISIBLE (-1500 -875);
FORCEADD VCCAUX15..1
(-3850 -900);
FORCEPROP 3 LASTPIN (-3850 -950) SIG_NAME P2V5_AUX\g
J 0
(-3840 -940);
DISPLAY 0.659574 (-3840 -940);
PAINT MONO (-3840 -940);
DISPLAY INVISIBLE (-3840 -940);
FORCEPROP 1 LAST HDL_POWER P2V5_AUX
J 1
(-3850 -850);
DISPLAY 0.702128 (-3850 -850);
PAINT GREEN (-3850 -850);
FORCEPROP 2 LAST CDS_LIB logical_power
J 0
(-3850 -900);
DISPLAY INVISIBLE (-3850 -900);
FORCEPROP 1 LAST PATH I269
J 0
(-3800 -875);
DISPLAY 0.872340 (-3800 -875);
PAINT AQUA (-3800 -875);
DISPLAY INVISIBLE (-3800 -875);
FORCEADD VCCAUX15..1
(-1650 -1450);
FORCEPROP 3 LASTPIN (-1650 -1500) SIG_NAME P1V2_AUX\g
J 0
(-1640 -1490);
DISPLAY 0.659574 (-1640 -1490);
PAINT MONO (-1640 -1490);
DISPLAY INVISIBLE (-1640 -1490);
FORCEPROP 1 LAST HDL_POWER P1V2_AUX
J 1
(-1650 -1400);
DISPLAY 0.702128 (-1650 -1400);
PAINT GREEN (-1650 -1400);
FORCEPROP 2 LAST CDS_LIB logical_power
J 0
(-1650 -1450);
DISPLAY INVISIBLE (-1650 -1450);
FORCEPROP 1 LAST PATH I270
J 0
(-1600 -1425);
DISPLAY 0.872340 (-1600 -1425);
PAINT AQUA (-1600 -1425);
DISPLAY INVISIBLE (-1600 -1425);
FORCEADD VCCAUX15..1
(-3950 -1450);
FORCEPROP 3 LASTPIN (-3950 -1500) SIG_NAME P1V2_AUX\g
J 0
(-3940 -1490);
DISPLAY 0.659574 (-3940 -1490);
PAINT MONO (-3940 -1490);
DISPLAY INVISIBLE (-3940 -1490);
FORCEPROP 1 LAST HDL_POWER P1V2_AUX
J 1
(-3950 -1400);
DISPLAY 0.702128 (-3950 -1400);
PAINT GREEN (-3950 -1400);
FORCEPROP 2 LAST CDS_LIB logical_power
J 0
(-3950 -1450);
DISPLAY INVISIBLE (-3950 -1450);
FORCEPROP 1 LAST PATH I271
J 0
(-3900 -1425);
DISPLAY 0.872340 (-3900 -1425);
PAINT AQUA (-3900 -1425);
DISPLAY INVISIBLE (-3900 -1425);
FORCEADD Q_INDUCTOR..1
R 6
(-125 650);
FORCEPROP 1 LAST PART_NUMBER CX8PG121009
J 0
(-250 516);
DISPLAY 0.510638 (-250 516);
PAINT WHITE (-250 516);
FORCEPROP 2 LAST VALUE BLM18PG121SN1D/2000MA
J 0
(-250 376);
DISPLAY 0.510638 (-250 376);
PAINT SKYBLUE (-250 376);
FORCEPROP 1 LAST MATERIAL IND
J 0
(-250 571);
DISPLAY 0.510638 (-250 571);
PAINT SKYBLUE (-250 571);
FORCEPROP 2 LAST PACK_TYPE SMLF
J 0
(-250 426);
DISPLAY 0.510638 (-250 426);
PAINT SKYBLUE (-250 426);
FORCEPROP 1 LAST PATH I272
J 0
(-50 561);
DISPLAY 0.723404 (-50 561);
PAINT GREEN (-50 561);
DISPLAY INVISIBLE (-50 561);
FORCEPROP 1 LAST NEEDS_NO_SIZE TRUE
J 0
(-125 628);
DISPLAY 0.468085 (-125 628);
PAINT GREEN (-125 628);
DISPLAY INVISIBLE (-125 628);
FORCEPROP 2 LAST CDS_LIB pure_quanta
J 0
(-125 603);
DISPLAY INVISIBLE (-125 603);
FORCEPROP 1 LAST LOCATION L2
J 0
(-250 457);
DISPLAY 0.702128 (-250 457);
PAINT YELLOW (-250 457);
FORCEPROP 2 LASTPIN (-225 675) $PN 1
J 2
(-235 627);
DISPLAY 0.808511 (-235 627);
PAINT WHITE (-235 627);
FORCEPROP 2 LASTPIN (-25 675) $PN 2
J 0
(-15 627);
DISPLAY 0.808511 (-15 627);
PAINT WHITE (-15 627);
FORCEPROP 2 LAST $SEC 1
J 0
(-250 318);
DISPLAY 0.680851 (-250 318);
PAINT MONO (-250 318);
DISPLAY INVISIBLE (-250 318);
FORCEPROP 0 LAST CDS_SEC 1
J 0
(-250 318);
DISPLAY 0.680851 (-250 318);
PAINT MONO (-250 318);
DISPLAY INVISIBLE (-250 318);
FORCEADD VCCAUX15..1
(-450 750);
FORCEPROP 3 LASTPIN (-450 700) SIG_NAME P1V2_AUX\g
J 0
(-440 710);
DISPLAY 0.659574 (-440 710);
PAINT MONO (-440 710);
DISPLAY INVISIBLE (-440 710);
FORCEPROP 1 LAST HDL_POWER P1V2_AUX
J 1
(-450 800);
DISPLAY 0.702128 (-450 800);
PAINT GREEN (-450 800);
FORCEPROP 2 LAST CDS_LIB logical_power
J 0
(-450 750);
DISPLAY INVISIBLE (-450 750);
FORCEPROP 1 LAST PATH I273
J 0
(-400 775);
DISPLAY 0.872340 (-400 775);
PAINT AQUA (-400 775);
DISPLAY INVISIBLE (-400 775);
FORCEADD MOSFET_NCH_4D1S..1
R 6
(3725 850);
FORCEPROP 2 LAST VALUE NTGS4141NT1G
J 0
(3875 793);
DISPLAY 0.680851 (3875 793);
FORCEPROP 1 LAST MATERIAL IC
J 0
(3855 942);
DISPLAY 0.723404 (3855 942);
PAINT GREEN (3855 942);
FORCEPROP 1 LAST PART_NUMBER BAM41410005
J 0
(3855 882);
DISPLAY 0.723404 (3855 882);
PAINT GREEN (3855 882);
FORCEPROP 2 LAST PART_TYPE SMLF
J 0
(3875 743);
DISPLAY 0.680851 (3875 743);
FORCEPROP 1 LAST CDS_LMAN_SYM_OUTLINE -125,125,125,-125
J 0
(3725 828);
DISPLAY 0.468085 (3725 828);
PAINT GREEN (3725 828);
DISPLAY INVISIBLE (3725 828);
FORCEPROP 1 LAST PIN_NAMES_ROTATE True
J 0
(3725 827);
DISPLAY 0.489362 (3725 827);
PAINT GREEN (3725 827);
DISPLAY INVISIBLE (3725 827);
FORCEPROP 2 LAST CDS_LIB pure_quanta
J 0
(3725 803);
DISPLAY INVISIBLE (3725 803);
FORCEPROP 2 LAST SEC_TYPE 
J 0
(3875 693);
DISPLAY 0.680851 (3875 693);
DISPLAY INVISIBLE (3875 693);
FORCEPROP 1 LAST PATH I274
J 0
(3850 941);
DISPLAY 0.723404 (3850 941);
PAINT GREEN (3850 941);
DISPLAY INVISIBLE (3850 941);
FORCEPROP 1 LAST LOCATION Q5
J 0
(3855 827);
DISPLAY 0.723404 (3855 827);
PAINT GREEN (3855 827);
FORCEPROP 0 LASTPIN (3650 675) $PN 1
R 1
J 2
(3640 665);
DISPLAY 0.680851 (3640 665);
PAINT MONO (3640 665);
FORCEPROP 0 LASTPIN (3700 675) $PN 2
R 1
J 2
(3690 665);
DISPLAY 0.680851 (3690 665);
PAINT MONO (3690 665);
FORCEPROP 0 LASTPIN (3550 925) $PN 3
J 2
(3540 935);
DISPLAY 0.680851 (3540 935);
PAINT MONO (3540 935);
FORCEPROP 0 LASTPIN (3750 1025) $PN 4
R 1
J 0
(3740 1035);
DISPLAY 0.680851 (3740 1035);
PAINT MONO (3740 1035);
FORCEPROP 0 LASTPIN (3750 675) $PN 5
R 1
J 2
(3740 665);
DISPLAY 0.680851 (3740 665);
PAINT MONO (3740 665);
FORCEPROP 0 LASTPIN (3800 675) $PN 6
R 1
J 2
(3790 665);
DISPLAY 0.680851 (3790 665);
PAINT MONO (3790 665);
FORCEPROP 2 LAST SEC 1
J 0
(3875 693);
DISPLAY 0.680851 (3875 693);
PAINT MONO (3875 693);
DISPLAY INVISIBLE (3875 693);
FORCEADD UNIVERSAL_POWER..1
(3750 1325);
FORCEPROP 3 LASTPIN (3750 1275) SIG_NAME P1V8_AUX\g
J 0
(3760 1285);
DISPLAY 0.659574 (3760 1285);
PAINT MONO (3760 1285);
DISPLAY INVISIBLE (3760 1285);
FORCEPROP 1 LAST HDL_POWER P1V8_AUX
J 1
(3750 1375);
DISPLAY 0.702128 (3750 1375);
PAINT GREEN (3750 1375);
FORCEPROP 2 LAST CDS_LIB logical_power
J 0
(3750 1325);
DISPLAY INVISIBLE (3750 1325);
FORCEPROP 1 LAST PATH I276
J 0
(3800 1350);
DISPLAY 0.872340 (3800 1350);
PAINT AQUA (3800 1350);
DISPLAY INVISIBLE (3800 1350);
FORCEADD Q_RES..2
(4350 800);
FORCEPROP 1 LAST PACK_TYPE 0603LF
J 0
(4390 625);
DISPLAY 0.978723 (4390 625);
FORCEPROP 1 LAST TOLERANCE 5%
J 0
(4395 825);
DISPLAY 0.978723 (4395 825);
FORCEPROP 1 LAST MATERIAL EMPTY
J 0
(4390 725);
DISPLAY 0.978723 (4390 725);
FORCEPROP 1 LAST VALUE 0
J 0
(4395 875);
DISPLAY 0.978723 (4395 875);
FORCEPROP 1 LAST PART_NUMBER CS00003J910
J 0
(4390 675);
DISPLAY 0.978723 (4390 675);
FORCEPROP 1 LAST WATTAGE 1/10W
J 0
(4390 775);
DISPLAY 0.978723 (4390 775);
FORCEPROP 2 LAST CDS_LIB pure_quanta
J 0
(4350 800);
DISPLAY INVISIBLE (4350 800);
FORCEPROP 1 LAST PATH I278
J 0
(4400 975);
DISPLAY 0.978723 (4400 975);
PAINT WHITE (4400 975);
DISPLAY INVISIBLE (4400 975);
FORCEPROP 1 LAST LOCATION R645
J 0
(4395 925);
DISPLAY 0.978723 (4395 925);
FORCEPROP 1 LASTPIN (4350 900) $PN 1
J 0
(4355 862);
DISPLAY 0.787234 (4355 862);
PAINT MONO (4355 862);
FORCEPROP 1 LASTPIN (4350 700) $PN 2
J 0
(4355 710);
DISPLAY 0.787234 (4355 710);
PAINT MONO (4355 710);
FORCEPROP 0 LAST $SEC 1
J 0
(4400 975);
DISPLAY 0.680851 (4400 975);
PAINT MONO (4400 975);
DISPLAY INVISIBLE (4400 975);
FORCEPROP 0 LAST CDS_SEC 1
J 0
(4400 975);
DISPLAY 0.680851 (4400 975);
DISPLAY INVISIBLE (4400 975);
FORCEADD Q_RES..2
(4350 0);
FORCEPROP 1 LAST VALUE 0
J 0
(4395 75);
DISPLAY 0.978723 (4395 75);
FORCEPROP 1 LAST WATTAGE 1/10W
J 0
(4390 -25);
DISPLAY 0.978723 (4390 -25);
FORCEPROP 1 LAST PACK_TYPE 0603LF
J 0
(4390 -175);
DISPLAY 0.978723 (4390 -175);
FORCEPROP 1 LAST PART_NUMBER CS00003J910
J 0
(4390 -125);
DISPLAY 0.978723 (4390 -125);
FORCEPROP 1 LAST MATERIAL EMPTY
J 0
(4390 -75);
DISPLAY 0.978723 (4390 -75);
FORCEPROP 1 LAST TOLERANCE 5%
J 0
(4395 25);
DISPLAY 0.978723 (4395 25);
FORCEPROP 2 LAST CDS_LIB pure_quanta
J 0
(4350 0);
DISPLAY INVISIBLE (4350 0);
FORCEPROP 1 LAST PATH I279
J 0
(4400 175);
DISPLAY 0.978723 (4400 175);
PAINT WHITE (4400 175);
DISPLAY INVISIBLE (4400 175);
FORCEPROP 1 LAST LOCATION R646
J 0
(4395 125);
DISPLAY 0.978723 (4395 125);
FORCEPROP 1 LASTPIN (4350 100) $PN 1
J 0
(4355 62);
DISPLAY 0.787234 (4355 62);
PAINT MONO (4355 62);
FORCEPROP 1 LASTPIN (4350 -100) $PN 2
J 0
(4355 -90);
DISPLAY 0.787234 (4355 -90);
PAINT MONO (4355 -90);
FORCEPROP 0 LAST $SEC 1
J 0
(4400 175);
DISPLAY 0.680851 (4400 175);
PAINT MONO (4400 175);
DISPLAY INVISIBLE (4400 175);
FORCEPROP 0 LAST CDS_SEC 1
J 0
(4400 175);
DISPLAY 0.680851 (4400 175);
DISPLAY INVISIBLE (4400 175);
FORCEADD UNIVERSAL_POWER..1
(4925 225);
FORCEPROP 3 LASTPIN (4925 175) SIG_NAME P3V3_AUX\g
J 0
(4935 185);
DISPLAY 0.659574 (4935 185);
PAINT MONO (4935 185);
DISPLAY INVISIBLE (4935 185);
FORCEPROP 1 LAST HDL_POWER P3V3_AUX
J 1
(4925 275);
DISPLAY 0.702128 (4925 275);
PAINT GREEN (4925 275);
FORCEPROP 2 LAST CDS_LIB logical_power
J 0
(4925 225);
DISPLAY INVISIBLE (4925 225);
FORCEPROP 1 LAST PATH I283
J 0
(4975 250);
DISPLAY 0.872340 (4975 250);
PAINT AQUA (4975 250);
DISPLAY INVISIBLE (4975 250);
FORCEADD Q_RES..2
(1725 -400);
FORCEPROP 1 LAST VALUE 150K
J 0
(1770 -325);
DISPLAY 0.510638 (1770 -325);
PAINT SKYBLUE (1770 -325);
FORCEPROP 1 LAST TOLERANCE 1%
J 0
(1770 -375);
DISPLAY 0.510638 (1770 -375);
PAINT SKYBLUE (1770 -375);
FORCEPROP 1 LAST WATTAGE 1/16W
J 0
(1765 -425);
DISPLAY 0.510638 (1765 -425);
PAINT SKYBLUE (1765 -425);
FORCEPROP 1 LAST PACK_TYPE 0402LF
J 0
(1765 -575);
DISPLAY 0.510638 (1765 -575);
PAINT SKYBLUE (1765 -575);
FORCEPROP 1 LAST PART_NUMBER CS41502FB04
J 0
(1765 -525);
DISPLAY 0.510638 (1765 -525);
PAINT WHITE (1765 -525);
FORCEPROP 1 LAST MATERIAL EMPTY
J 0
(1765 -475);
DISPLAY 0.510638 (1765 -475);
PAINT SKYBLUE (1765 -475);
FORCEPROP 2 LAST CDS_LIB pure_quanta
J 0
(1725 -400);
DISPLAY INVISIBLE (1725 -400);
FORCEPROP 1 LAST PATH I284
J 0
(1775 -225);
DISPLAY 0.978723 (1775 -225);
PAINT WHITE (1775 -225);
DISPLAY INVISIBLE (1775 -225);
FORCEPROP 1 LAST LOCATION R493
J 0
(1770 -275);
DISPLAY 0.702128 (1770 -275);
PAINT YELLOW (1770 -275);
FORCEPROP 0 LAST $SEC 1
J 0
(1775 -225);
DISPLAY INVISIBLE (1775 -225);
FORCEPROP 0 LAST CDS_SEC 1
J 0
(1775 -225);
DISPLAY 0.680851 (1775 -225);
DISPLAY INVISIBLE (1775 -225);
FORCEPROP 1 LASTPIN (1725 -300) $PN 1
J 0
(1730 -338);
DISPLAY 0.808511 (1730 -338);
PAINT WHITE (1730 -338);
DISPLAY INVISIBLE (1730 -338);
FORCEPROP 1 LASTPIN (1725 -500) $PN 2
J 0
(1730 -490);
DISPLAY 0.808511 (1730 -490);
PAINT WHITE (1730 -490);
DISPLAY INVISIBLE (1730 -490);
FORCEADD UNIVERSAL_GND..1
(1725 -700);
FORCEPROP 3 LASTPIN (1725 -650) SIG_NAME GND\g
J 0
(1735 -640);
DISPLAY 0.659574 (1735 -640);
PAINT MONO (1735 -640);
DISPLAY INVISIBLE (1735 -640);
FORCEPROP 2 LAST CDS_LIB logical_power
J 0
(1725 -700);
DISPLAY INVISIBLE (1725 -700);
FORCEPROP 1 LAST HDL_POWER GND
J 1
(1750 -775);
DISPLAY 0.702128 (1750 -775);
PAINT GREEN (1750 -775);
DISPLAY INVISIBLE (1750 -775);
FORCEPROP 1 LAST PATH I285
J 0
(1800 -700);
DISPLAY 0.872340 (1800 -700);
PAINT AQUA (1800 -700);
DISPLAY INVISIBLE (1800 -700);
FORCEADD AST2600A3GP..6
(-3075 1675);
FORCEPROP 1 LAST MATERIAL IC
J 0
(-3435 3752);
DISPLAY 0.723404 (-3435 3752);
FORCEPROP 1 LAST PART_NUMBER AJ026000T06
J 0
(-3435 3879);
DISPLAY 0.723404 (-3435 3879);
FORCEPROP 2 LAST PART_TYPE SMLF
J 0
(-3425 4125);
DISPLAY 0.680851 (-3425 4125);
FORCEPROP 2 LAST VALUE AST2600A3-GP
J 0
(-3425 4075);
DISPLAY 0.680851 (-3425 4075);
FORCEPROP 2 LAST CDS_LIB pure_quanta
J 0
(-3075 1675);
DISPLAY INVISIBLE (-3075 1675);
FORCEPROP 1 LAST PATH I286
J 0
(-3075 1675);
DISPLAY 0.723404 (-3075 1675);
DISPLAY INVISIBLE (-3075 1675);
FORCEPROP 1 LAST CDS_LMAN_SYM_OUTLINE -375,2050,375,-2050
J 0
(-3075 1675);
DISPLAY 0.468085 (-3075 1675);
PAINT GREEN (-3075 1675);
DISPLAY INVISIBLE (-3075 1675);
FORCEPROP 1 LAST NEEDS_NO_SIZE TRUE
J 0
(-3075 1675);
DISPLAY 0.723404 (-3075 1675);
DISPLAY INVISIBLE (-3075 1675);
FORCEPROP 1 LAST LOCATION U5
J 0
(-3435 4026);
DISPLAY 0.723404 (-3435 4026);
FORCEPROP 0 LASTPIN (-3600 3625) $PN A1
J 2
(-3610 3635);
DISPLAY 0.680851 (-3610 3635);
PAINT MONO (-3610 3635);
FORCEPROP 0 LASTPIN (-3600 3575) $PN A5
J 2
(-3610 3585);
DISPLAY 0.680851 (-3610 3585);
PAINT MONO (-3610 3585);
FORCEPROP 0 LASTPIN (-3600 3525) $PN A26
J 2
(-3610 3535);
DISPLAY 0.680851 (-3610 3535);
PAINT MONO (-3610 3535);
FORCEPROP 0 LASTPIN (-2550 1325) $PN AA1
J 0
(-2540 1335);
DISPLAY 0.680851 (-2540 1335);
PAINT MONO (-2540 1335);
FORCEPROP 0 LASTPIN (-2550 1275) $PN AA3
J 0
(-2540 1285);
DISPLAY 0.680851 (-2540 1285);
PAINT MONO (-2540 1285);
FORCEPROP 0 LASTPIN (-2550 1225) $PN AA6
J 0
(-2540 1235);
DISPLAY 0.680851 (-2540 1235);
PAINT MONO (-2540 1235);
FORCEPROP 0 LASTPIN (-2550 1175) $PN AA7
J 0
(-2540 1185);
DISPLAY 0.680851 (-2540 1185);
PAINT MONO (-2540 1185);
FORCEPROP 0 LASTPIN (-2550 1125) $PN AA8
J 0
(-2540 1135);
DISPLAY 0.680851 (-2540 1135);
PAINT MONO (-2540 1135);
FORCEPROP 0 LASTPIN (-2550 1075) $PN AA10
J 0
(-2540 1085);
DISPLAY 0.680851 (-2540 1085);
PAINT MONO (-2540 1085);
FORCEPROP 0 LASTPIN (-2550 1025) $PN AA14
J 0
(-2540 1035);
DISPLAY 0.680851 (-2540 1035);
PAINT MONO (-2540 1035);
FORCEPROP 0 LASTPIN (-2550 975) $PN AA15
J 0
(-2540 985);
DISPLAY 0.680851 (-2540 985);
PAINT MONO (-2540 985);
FORCEPROP 0 LASTPIN (-2550 925) $PN AA19
J 0
(-2540 935);
DISPLAY 0.680851 (-2540 935);
PAINT MONO (-2540 935);
FORCEPROP 0 LASTPIN (-2550 875) $PN AA20
J 0
(-2540 885);
DISPLAY 0.680851 (-2540 885);
PAINT MONO (-2540 885);
FORCEPROP 0 LASTPIN (-2550 825) $PN AA22
J 0
(-2540 835);
DISPLAY 0.680851 (-2540 835);
PAINT MONO (-2540 835);
FORCEPROP 0 LASTPIN (-2550 775) $PN AC2
J 0
(-2540 785);
DISPLAY 0.680851 (-2540 785);
PAINT MONO (-2540 785);
FORCEPROP 0 LASTPIN (-2550 725) $PN AC6
J 0
(-2540 735);
DISPLAY 0.680851 (-2540 735);
PAINT MONO (-2540 735);
FORCEPROP 0 LASTPIN (-2550 675) $PN AC25
J 0
(-2540 685);
DISPLAY 0.680851 (-2540 685);
PAINT MONO (-2540 685);
FORCEPROP 0 LASTPIN (-2550 625) $PN AD1
J 0
(-2540 635);
DISPLAY 0.680851 (-2540 635);
PAINT MONO (-2540 635);
FORCEPROP 0 LASTPIN (-2550 575) $PN AD4
J 0
(-2540 585);
DISPLAY 0.680851 (-2540 585);
PAINT MONO (-2540 585);
FORCEPROP 0 LASTPIN (-2550 525) $PN AE3
J 0
(-2540 535);
DISPLAY 0.680851 (-2540 535);
PAINT MONO (-2540 535);
FORCEPROP 0 LASTPIN (-2550 475) $PN AE6
J 0
(-2540 485);
DISPLAY 0.680851 (-2540 485);
PAINT MONO (-2540 485);
FORCEPROP 0 LASTPIN (-2550 425) $PN AE9
J 0
(-2540 435);
DISPLAY 0.680851 (-2540 435);
PAINT MONO (-2540 435);
FORCEPROP 0 LASTPIN (-2550 375) $PN AE13
J 0
(-2540 385);
DISPLAY 0.680851 (-2540 385);
PAINT MONO (-2540 385);
FORCEPROP 0 LASTPIN (-2550 325) $PN AE17
J 0
(-2540 335);
DISPLAY 0.680851 (-2540 335);
PAINT MONO (-2540 335);
FORCEPROP 0 LASTPIN (-2550 275) $PN AE20
J 0
(-2540 285);
DISPLAY 0.680851 (-2540 285);
PAINT MONO (-2540 285);
FORCEPROP 0 LASTPIN (-2550 225) $PN AE23
J 0
(-2540 235);
DISPLAY 0.680851 (-2540 235);
PAINT MONO (-2540 235);
FORCEPROP 0 LASTPIN (-2550 175) $PN AF1
J 0
(-2540 185);
DISPLAY 0.680851 (-2540 185);
PAINT MONO (-2540 185);
FORCEPROP 0 LASTPIN (-2550 125) $PN AF4
J 0
(-2540 135);
DISPLAY 0.680851 (-2540 135);
PAINT MONO (-2540 135);
FORCEPROP 0 LASTPIN (-2550 75) $PN AF26
J 0
(-2540 85);
DISPLAY 0.680851 (-2540 85);
PAINT MONO (-2540 85);
FORCEPROP 0 LASTPIN (-3600 3475) $PN B5
J 2
(-3610 3485);
DISPLAY 0.680851 (-3610 3485);
PAINT MONO (-3610 3485);
FORCEPROP 0 LASTPIN (-3600 3425) $PN B11
J 2
(-3610 3435);
DISPLAY 0.680851 (-3610 3435);
PAINT MONO (-3610 3435);
FORCEPROP 0 LASTPIN (-3600 3375) $PN B15
J 2
(-3610 3385);
DISPLAY 0.680851 (-3610 3385);
PAINT MONO (-3610 3385);
FORCEPROP 0 LASTPIN (-3600 3325) $PN B19
J 2
(-3610 3335);
DISPLAY 0.680851 (-3610 3335);
PAINT MONO (-3610 3335);
FORCEPROP 0 LASTPIN (-3600 3275) $PN B23
J 2
(-3610 3285);
DISPLAY 0.680851 (-3610 3285);
PAINT MONO (-3610 3285);
FORCEPROP 0 LASTPIN (-3600 3225) $PN C3
J 2
(-3610 3235);
DISPLAY 0.680851 (-3610 3235);
PAINT MONO (-3610 3235);
FORCEPROP 0 LASTPIN (-3600 3175) $PN D25
J 2
(-3610 3185);
DISPLAY 0.680851 (-3610 3185);
PAINT MONO (-3610 3185);
FORCEPROP 0 LASTPIN (-3600 3125) $PN E8
J 2
(-3610 3135);
DISPLAY 0.680851 (-3610 3135);
PAINT MONO (-3610 3135);
FORCEPROP 0 LASTPIN (-3600 3075) $PN F6
J 2
(-3610 3085);
DISPLAY 0.680851 (-3610 3085);
PAINT MONO (-3610 3085);
FORCEPROP 0 LASTPIN (-3600 3025) $PN F8
J 2
(-3610 3035);
DISPLAY 0.680851 (-3610 3035);
PAINT MONO (-3610 3035);
FORCEPROP 0 LASTPIN (-3600 2975) $PN F10
J 2
(-3610 2985);
DISPLAY 0.680851 (-3610 2985);
PAINT MONO (-3610 2985);
FORCEPROP 0 LASTPIN (-3600 2925) $PN F12
J 2
(-3610 2935);
DISPLAY 0.680851 (-3610 2935);
PAINT MONO (-3610 2935);
FORCEPROP 0 LASTPIN (-3600 2875) $PN F14
J 2
(-3610 2885);
DISPLAY 0.680851 (-3610 2885);
PAINT MONO (-3610 2885);
FORCEPROP 0 LASTPIN (-3600 2825) $PN F16
J 2
(-3610 2835);
DISPLAY 0.680851 (-3610 2835);
PAINT MONO (-3610 2835);
FORCEPROP 0 LASTPIN (-3600 2775) $PN F17
J 2
(-3610 2785);
DISPLAY 0.680851 (-3610 2785);
PAINT MONO (-3610 2785);
FORCEPROP 0 LASTPIN (-3600 2725) $PN F18
J 2
(-3610 2735);
DISPLAY 0.680851 (-3610 2735);
PAINT MONO (-3610 2735);
FORCEPROP 0 LASTPIN (-3600 2675) $PN F21
J 2
(-3610 2685);
DISPLAY 0.680851 (-3610 2685);
PAINT MONO (-3610 2685);
FORCEPROP 0 LASTPIN (-3600 2625) $PN G2
J 2
(-3610 2635);
DISPLAY 0.680851 (-3610 2635);
PAINT MONO (-3610 2635);
FORCEPROP 0 LASTPIN (-3600 2575) $PN G25
J 2
(-3610 2585);
DISPLAY 0.680851 (-3610 2585);
PAINT MONO (-3610 2585);
FORCEPROP 0 LASTPIN (-3600 2525) $PN H4
J 2
(-3610 2535);
DISPLAY 0.680851 (-3610 2535);
PAINT MONO (-3610 2535);
FORCEPROP 0 LASTPIN (-3600 2475) $PN H9
J 2
(-3610 2485);
DISPLAY 0.680851 (-3610 2485);
PAINT MONO (-3610 2485);
FORCEPROP 0 LASTPIN (-3600 2425) $PN H10
J 2
(-3610 2435);
DISPLAY 0.680851 (-3610 2435);
PAINT MONO (-3610 2435);
FORCEPROP 0 LASTPIN (-3600 2375) $PN H11
J 2
(-3610 2385);
DISPLAY 0.680851 (-3610 2385);
PAINT MONO (-3610 2385);
FORCEPROP 0 LASTPIN (-3600 2325) $PN H13
J 2
(-3610 2335);
DISPLAY 0.680851 (-3610 2335);
PAINT MONO (-3610 2335);
FORCEPROP 0 LASTPIN (-3600 2275) $PN J2
J 2
(-3610 2285);
DISPLAY 0.680851 (-3610 2285);
PAINT MONO (-3610 2285);
FORCEPROP 0 LASTPIN (-3600 2225) $PN J11
J 2
(-3610 2235);
DISPLAY 0.680851 (-3610 2235);
PAINT MONO (-3610 2235);
FORCEPROP 0 LASTPIN (-3600 2175) $PN J13
J 2
(-3610 2185);
DISPLAY 0.680851 (-3610 2185);
PAINT MONO (-3610 2185);
FORCEPROP 0 LASTPIN (-3600 2125) $PN J14
J 2
(-3610 2135);
DISPLAY 0.680851 (-3610 2135);
PAINT MONO (-3610 2135);
FORCEPROP 0 LASTPIN (-3600 2075) $PN J15
J 2
(-3610 2085);
DISPLAY 0.680851 (-3610 2085);
PAINT MONO (-3610 2085);
FORCEPROP 0 LASTPIN (-3600 2025) $PN J16
J 2
(-3610 2035);
DISPLAY 0.680851 (-3610 2035);
PAINT MONO (-3610 2035);
FORCEPROP 0 LASTPIN (-3600 1975) $PN J17
J 2
(-3610 1985);
DISPLAY 0.680851 (-3610 1985);
PAINT MONO (-3610 1985);
FORCEPROP 0 LASTPIN (-3600 1925) $PN J18
J 2
(-3610 1935);
DISPLAY 0.680851 (-3610 1935);
PAINT MONO (-3610 1935);
FORCEPROP 0 LASTPIN (-3600 1875) $PN J19
J 2
(-3610 1885);
DISPLAY 0.680851 (-3610 1885);
PAINT MONO (-3610 1885);
FORCEPROP 0 LASTPIN (-3600 1825) $PN K4
J 2
(-3610 1835);
DISPLAY 0.680851 (-3610 1835);
PAINT MONO (-3610 1835);
FORCEPROP 0 LASTPIN (-3600 1775) $PN K8
J 2
(-3610 1785);
DISPLAY 0.680851 (-3610 1785);
PAINT MONO (-3610 1785);
FORCEPROP 0 LASTPIN (-3600 1725) $PN K9
J 2
(-3610 1735);
DISPLAY 0.680851 (-3610 1735);
PAINT MONO (-3610 1735);
FORCEPROP 0 LASTPIN (-3600 1675) $PN K13
J 2
(-3610 1685);
DISPLAY 0.680851 (-3610 1685);
PAINT MONO (-3610 1685);
FORCEPROP 0 LASTPIN (-3600 1625) $PN K14
J 2
(-3610 1635);
DISPLAY 0.680851 (-3610 1635);
PAINT MONO (-3610 1635);
FORCEPROP 0 LASTPIN (-3600 1575) $PN K15
J 2
(-3610 1585);
DISPLAY 0.680851 (-3610 1585);
PAINT MONO (-3610 1585);
FORCEPROP 0 LASTPIN (-3600 1525) $PN K22
J 2
(-3610 1535);
DISPLAY 0.680851 (-3610 1535);
PAINT MONO (-3610 1535);
FORCEPROP 0 LASTPIN (-3600 1475) $PN L2
J 2
(-3610 1485);
DISPLAY 0.680851 (-3610 1485);
PAINT MONO (-3610 1485);
FORCEPROP 0 LASTPIN (-3600 1425) $PN L8
J 2
(-3610 1435);
DISPLAY 0.680851 (-3610 1435);
PAINT MONO (-3610 1435);
FORCEPROP 0 LASTPIN (-3600 1375) $PN L11
J 2
(-3610 1385);
DISPLAY 0.680851 (-3610 1385);
PAINT MONO (-3610 1385);
FORCEPROP 0 LASTPIN (-3600 1325) $PN L12
J 2
(-3610 1335);
DISPLAY 0.680851 (-3610 1335);
PAINT MONO (-3610 1335);
FORCEPROP 0 LASTPIN (-3600 1275) $PN L15
J 2
(-3610 1285);
DISPLAY 0.680851 (-3610 1285);
PAINT MONO (-3610 1285);
FORCEPROP 0 LASTPIN (-3600 1225) $PN L16
J 2
(-3610 1235);
DISPLAY 0.680851 (-3610 1235);
PAINT MONO (-3610 1235);
FORCEPROP 0 LASTPIN (-3600 1175) $PN L17
J 2
(-3610 1185);
DISPLAY 0.680851 (-3610 1185);
PAINT MONO (-3610 1185);
FORCEPROP 0 LASTPIN (-3600 1125) $PN L18
J 2
(-3610 1135);
DISPLAY 0.680851 (-3610 1135);
PAINT MONO (-3610 1135);
FORCEPROP 0 LASTPIN (-3600 1075) $PN L19
J 2
(-3610 1085);
DISPLAY 0.680851 (-3610 1085);
PAINT MONO (-3610 1085);
FORCEPROP 0 LASTPIN (-3600 1025) $PN L25
J 2
(-3610 1035);
DISPLAY 0.680851 (-3610 1035);
PAINT MONO (-3610 1035);
FORCEPROP 0 LASTPIN (-3600 975) $PN M4
J 2
(-3610 985);
DISPLAY 0.680851 (-3610 985);
PAINT MONO (-3610 985);
FORCEPROP 0 LASTPIN (-3600 925) $PN M9
J 2
(-3610 935);
DISPLAY 0.680851 (-3610 935);
PAINT MONO (-3610 935);
FORCEPROP 0 LASTPIN (-3600 875) $PN M10
J 2
(-3610 885);
DISPLAY 0.680851 (-3610 885);
PAINT MONO (-3610 885);
FORCEPROP 0 LASTPIN (-3600 825) $PN M12
J 2
(-3610 835);
DISPLAY 0.680851 (-3610 835);
PAINT MONO (-3610 835);
FORCEPROP 0 LASTPIN (-3600 775) $PN M15
J 2
(-3610 785);
DISPLAY 0.680851 (-3610 785);
PAINT MONO (-3610 785);
FORCEPROP 0 LASTPIN (-3600 725) $PN M16
J 2
(-3610 735);
DISPLAY 0.680851 (-3610 735);
PAINT MONO (-3610 735);
FORCEPROP 0 LASTPIN (-3600 675) $PN M17
J 2
(-3610 685);
DISPLAY 0.680851 (-3610 685);
PAINT MONO (-3610 685);
FORCEPROP 0 LASTPIN (-3600 625) $PN M18
J 2
(-3610 635);
DISPLAY 0.680851 (-3610 635);
PAINT MONO (-3610 635);
FORCEPROP 0 LASTPIN (-3600 575) $PN M19
J 2
(-3610 585);
DISPLAY 0.680851 (-3610 585);
PAINT MONO (-3610 585);
FORCEPROP 0 LASTPIN (-3600 525) $PN N2
J 2
(-3610 535);
DISPLAY 0.680851 (-3610 535);
PAINT MONO (-3610 535);
FORCEPROP 0 LASTPIN (-3600 475) $PN N6
J 2
(-3610 485);
DISPLAY 0.680851 (-3610 485);
PAINT MONO (-3610 485);
FORCEPROP 0 LASTPIN (-3600 425) $PN N9
J 2
(-3610 435);
DISPLAY 0.680851 (-3610 435);
PAINT MONO (-3610 435);
FORCEPROP 0 LASTPIN (-3600 375) $PN N10
J 2
(-3610 385);
DISPLAY 0.680851 (-3610 385);
PAINT MONO (-3610 385);
FORCEPROP 0 LASTPIN (-3600 325) $PN N15
J 2
(-3610 335);
DISPLAY 0.680851 (-3610 335);
PAINT MONO (-3610 335);
FORCEPROP 0 LASTPIN (-3600 275) $PN N16
J 2
(-3610 285);
DISPLAY 0.680851 (-3610 285);
PAINT MONO (-3610 285);
FORCEPROP 0 LASTPIN (-3600 225) $PN N17
J 2
(-3610 235);
DISPLAY 0.680851 (-3610 235);
PAINT MONO (-3610 235);
FORCEPROP 0 LASTPIN (-3600 175) $PN N18
J 2
(-3610 185);
DISPLAY 0.680851 (-3610 185);
PAINT MONO (-3610 185);
FORCEPROP 0 LASTPIN (-3600 125) $PN N19
J 2
(-3610 135);
DISPLAY 0.680851 (-3610 135);
PAINT MONO (-3610 135);
FORCEPROP 0 LASTPIN (-3600 75) $PN P4
J 2
(-3610 85);
DISPLAY 0.680851 (-3610 85);
PAINT MONO (-3610 85);
FORCEPROP 0 LASTPIN (-3600 25) $PN P9
J 2
(-3610 35);
DISPLAY 0.680851 (-3610 35);
PAINT MONO (-3610 35);
FORCEPROP 0 LASTPIN (-3600 -25) $PN P10
J 2
(-3610 -15);
DISPLAY 0.680851 (-3610 -15);
PAINT MONO (-3610 -15);
FORCEPROP 0 LASTPIN (-3600 -75) $PN P15
J 2
(-3610 -65);
DISPLAY 0.680851 (-3610 -65);
PAINT MONO (-3610 -65);
FORCEPROP 0 LASTPIN (-3600 -125) $PN P16
J 2
(-3610 -115);
DISPLAY 0.680851 (-3610 -115);
PAINT MONO (-3610 -115);
FORCEPROP 0 LASTPIN (-3600 -175) $PN P17
J 2
(-3610 -165);
DISPLAY 0.680851 (-3610 -165);
PAINT MONO (-3610 -165);
FORCEPROP 0 LASTPIN (-3600 -225) $PN P18
J 2
(-3610 -215);
DISPLAY 0.680851 (-3610 -215);
PAINT MONO (-3610 -215);
FORCEPROP 0 LASTPIN (-3600 -275) $PN P19
J 2
(-3610 -265);
DISPLAY 0.680851 (-3610 -265);
PAINT MONO (-3610 -265);
FORCEPROP 0 LASTPIN (-2550 3625) $PN R2
J 0
(-2540 3635);
DISPLAY 0.680851 (-2540 3635);
PAINT MONO (-2540 3635);
FORCEPROP 0 LASTPIN (-2550 3575) $PN R8
J 0
(-2540 3585);
DISPLAY 0.680851 (-2540 3585);
PAINT MONO (-2540 3585);
FORCEPROP 0 LASTPIN (-2550 3525) $PN R11
J 0
(-2540 3535);
DISPLAY 0.680851 (-2540 3535);
PAINT MONO (-2540 3535);
FORCEPROP 0 LASTPIN (-2550 3475) $PN R15
J 0
(-2540 3485);
DISPLAY 0.680851 (-2540 3485);
PAINT MONO (-2540 3485);
FORCEPROP 0 LASTPIN (-2550 3425) $PN R16
J 0
(-2540 3435);
DISPLAY 0.680851 (-2540 3435);
PAINT MONO (-2540 3435);
FORCEPROP 0 LASTPIN (-2550 3375) $PN R17
J 0
(-2540 3385);
DISPLAY 0.680851 (-2540 3385);
PAINT MONO (-2540 3385);
FORCEPROP 0 LASTPIN (-2550 3325) $PN R18
J 0
(-2540 3335);
DISPLAY 0.680851 (-2540 3335);
PAINT MONO (-2540 3335);
FORCEPROP 0 LASTPIN (-2550 3275) $PN R19
J 0
(-2540 3285);
DISPLAY 0.680851 (-2540 3285);
PAINT MONO (-2540 3285);
FORCEPROP 0 LASTPIN (-2550 3225) $PN R25
J 0
(-2540 3235);
DISPLAY 0.680851 (-2540 3235);
PAINT MONO (-2540 3235);
FORCEPROP 0 LASTPIN (-2550 3175) $PN T4
J 0
(-2540 3185);
DISPLAY 0.680851 (-2540 3185);
PAINT MONO (-2540 3185);
FORCEPROP 0 LASTPIN (-2550 3125) $PN T11
J 0
(-2540 3135);
DISPLAY 0.680851 (-2540 3135);
PAINT MONO (-2540 3135);
FORCEPROP 0 LASTPIN (-2550 3075) $PN T12
J 0
(-2540 3085);
DISPLAY 0.680851 (-2540 3085);
PAINT MONO (-2540 3085);
FORCEPROP 0 LASTPIN (-2550 3025) $PN T15
J 0
(-2540 3035);
DISPLAY 0.680851 (-2540 3035);
PAINT MONO (-2540 3035);
FORCEPROP 0 LASTPIN (-2550 2975) $PN T16
J 0
(-2540 2985);
DISPLAY 0.680851 (-2540 2985);
PAINT MONO (-2540 2985);
FORCEPROP 0 LASTPIN (-2550 2925) $PN T17
J 0
(-2540 2935);
DISPLAY 0.680851 (-2540 2935);
PAINT MONO (-2540 2935);
FORCEPROP 0 LASTPIN (-2550 2875) $PN T18
J 0
(-2540 2885);
DISPLAY 0.680851 (-2540 2885);
PAINT MONO (-2540 2885);
FORCEPROP 0 LASTPIN (-2550 2825) $PN T19
J 0
(-2540 2835);
DISPLAY 0.680851 (-2540 2835);
PAINT MONO (-2540 2835);
FORCEPROP 0 LASTPIN (-2550 2775) $PN U2
J 0
(-2540 2785);
DISPLAY 0.680851 (-2540 2785);
PAINT MONO (-2540 2785);
FORCEPROP 0 LASTPIN (-2550 2725) $PN U8
J 0
(-2540 2735);
DISPLAY 0.680851 (-2540 2735);
PAINT MONO (-2540 2735);
FORCEPROP 0 LASTPIN (-2550 2675) $PN U9
J 0
(-2540 2685);
DISPLAY 0.680851 (-2540 2685);
PAINT MONO (-2540 2685);
FORCEPROP 0 LASTPIN (-2550 2625) $PN U10
J 0
(-2540 2635);
DISPLAY 0.680851 (-2540 2635);
PAINT MONO (-2540 2635);
FORCEPROP 0 LASTPIN (-2550 2575) $PN U11
J 0
(-2540 2585);
DISPLAY 0.680851 (-2540 2585);
PAINT MONO (-2540 2585);
FORCEPROP 0 LASTPIN (-2550 2525) $PN U12
J 0
(-2540 2535);
DISPLAY 0.680851 (-2540 2535);
PAINT MONO (-2540 2535);
FORCEPROP 0 LASTPIN (-2550 2475) $PN U14
J 0
(-2540 2485);
DISPLAY 0.680851 (-2540 2485);
PAINT MONO (-2540 2485);
FORCEPROP 0 LASTPIN (-2550 2425) $PN U19
J 0
(-2540 2435);
DISPLAY 0.680851 (-2540 2435);
PAINT MONO (-2540 2435);
FORCEPROP 0 LASTPIN (-2550 2375) $PN U22
J 0
(-2540 2385);
DISPLAY 0.680851 (-2540 2385);
PAINT MONO (-2540 2385);
FORCEPROP 0 LASTPIN (-2550 -275) $PN U23
J 0
(-2540 -265);
DISPLAY 0.680851 (-2540 -265);
PAINT MONO (-2540 -265);
FORCEPROP 0 LASTPIN (-2550 2325) $PN V5
J 0
(-2540 2335);
DISPLAY 0.680851 (-2540 2335);
PAINT MONO (-2540 2335);
FORCEPROP 0 LASTPIN (-2550 2275) $PN V11
J 0
(-2540 2285);
DISPLAY 0.680851 (-2540 2285);
PAINT MONO (-2540 2285);
FORCEPROP 0 LASTPIN (-2550 2225) $PN V12
J 0
(-2540 2235);
DISPLAY 0.680851 (-2540 2235);
PAINT MONO (-2540 2235);
FORCEPROP 0 LASTPIN (-2550 2175) $PN V14
J 0
(-2540 2185);
DISPLAY 0.680851 (-2540 2185);
PAINT MONO (-2540 2185);
FORCEPROP 0 LASTPIN (-2550 2125) $PN V15
J 0
(-2540 2135);
DISPLAY 0.680851 (-2540 2135);
PAINT MONO (-2540 2135);
FORCEPROP 0 LASTPIN (-2550 2075) $PN V16
J 0
(-2540 2085);
DISPLAY 0.680851 (-2540 2085);
PAINT MONO (-2540 2085);
FORCEPROP 0 LASTPIN (-2550 2025) $PN V17
J 0
(-2540 2035);
DISPLAY 0.680851 (-2540 2035);
PAINT MONO (-2540 2035);
FORCEPROP 0 LASTPIN (-2550 1975) $PN V18
J 0
(-2540 1985);
DISPLAY 0.680851 (-2540 1985);
PAINT MONO (-2540 1985);
FORCEPROP 0 LASTPIN (-2550 1925) $PN V19
J 0
(-2540 1935);
DISPLAY 0.680851 (-2540 1935);
PAINT MONO (-2540 1935);
FORCEPROP 0 LASTPIN (-2550 1875) $PN W5
J 0
(-2540 1885);
DISPLAY 0.680851 (-2540 1885);
PAINT MONO (-2540 1885);
FORCEPROP 0 LASTPIN (-2550 1825) $PN W6
J 0
(-2540 1835);
DISPLAY 0.680851 (-2540 1835);
PAINT MONO (-2540 1835);
FORCEPROP 0 LASTPIN (-2550 1775) $PN W8
J 0
(-2540 1785);
DISPLAY 0.680851 (-2540 1785);
PAINT MONO (-2540 1785);
FORCEPROP 0 LASTPIN (-2550 1725) $PN W9
J 0
(-2540 1735);
DISPLAY 0.680851 (-2540 1735);
PAINT MONO (-2540 1735);
FORCEPROP 0 LASTPIN (-2550 1675) $PN W10
J 0
(-2540 1685);
DISPLAY 0.680851 (-2540 1685);
PAINT MONO (-2540 1685);
FORCEPROP 0 LASTPIN (-2550 1625) $PN W11
J 0
(-2540 1635);
DISPLAY 0.680851 (-2540 1635);
PAINT MONO (-2540 1635);
FORCEPROP 0 LASTPIN (-2550 1575) $PN W12
J 0
(-2540 1585);
DISPLAY 0.680851 (-2540 1585);
PAINT MONO (-2540 1585);
FORCEPROP 0 LASTPIN (-2550 1525) $PN W22
J 0
(-2540 1535);
DISPLAY 0.680851 (-2540 1535);
PAINT MONO (-2540 1535);
FORCEPROP 0 LASTPIN (-2550 1475) $PN W25
J 0
(-2540 1485);
DISPLAY 0.680851 (-2540 1485);
PAINT MONO (-2540 1485);
FORCEPROP 0 LASTPIN (-2550 1425) $PN Y6
J 0
(-2540 1435);
DISPLAY 0.680851 (-2540 1435);
PAINT MONO (-2540 1435);
FORCEPROP 0 LASTPIN (-2550 1375) $PN Y22
J 0
(-2540 1385);
DISPLAY 0.680851 (-2540 1385);
PAINT MONO (-2540 1385);
FORCEPROP 0 LAST $SEC 6
J 0
(-3425 4175);
DISPLAY 0.680851 (-3425 4175);
PAINT MONO (-3425 4175);
DISPLAY INVISIBLE (-3425 4175);
FORCEPROP 0 LAST CDS_SEC 6
J 0
(-3425 4175);
DISPLAY 0.680851 (-3425 4175);
DISPLAY INVISIBLE (-3425 4175);
FORCEADD MOSFET_PCH_GDS..1
R 6
(3475 -125);
FORCEPROP 2 LAST VALUE NTR1P02LT1G
J 0
(3625 -232);
DISPLAY 0.680851 (3625 -232);
FORCEPROP 2 LAST PART_TYPE SMLF
J 0
(3625 -282);
DISPLAY 0.680851 (3625 -282);
FORCEPROP 1 LAST PART_NUMBER BAM1P020000
J 0
(3602 -189);
DISPLAY 0.723404 (3602 -189);
PAINT GREEN (3602 -189);
FORCEPROP 1 LAST MATERIAL EMPTY
J 0
(3602 -74);
DISPLAY 0.723404 (3602 -74);
PAINT GREEN (3602 -74);
FORCEPROP 2 LAST CDS_LIB pure_quanta
J 0
(3475 -172);
DISPLAY INVISIBLE (3475 -172);
FORCEPROP 1 LAST PATH I289
J 0
(3475 -159);
DISPLAY 0.723404 (3475 -159);
PAINT GREEN (3475 -159);
DISPLAY INVISIBLE (3475 -159);
FORCEPROP 1 LAST PIN_NAMES_ROTATE True
J 0
(3475 -148);
DISPLAY 0.489362 (3475 -148);
PAINT GREEN (3475 -148);
DISPLAY INVISIBLE (3475 -148);
FORCEPROP 1 LAST CDS_LMAN_SYM_OUTLINE -125,100,125,-100
J 0
(3475 -147);
DISPLAY 0.468085 (3475 -147);
PAINT GREEN (3475 -147);
DISPLAY INVISIBLE (3475 -147);
FORCEPROP 1 LAST LOCATION Q4
J 0
(3602 -134);
DISPLAY 0.723404 (3602 -134);
PAINT GREEN (3602 -134);
FORCEPROP 0 LASTPIN (3500 25) $PN D
R 1
J 0
(3490 35);
DISPLAY 0.680851 (3490 35);
PAINT MONO (3490 35);
FORCEPROP 0 LASTPIN (3300 -175) $PN G
J 2
(3290 -165);
DISPLAY 0.680851 (3290 -165);
PAINT MONO (3290 -165);
FORCEPROP 0 LASTPIN (3500 -275) $PN S
R 1
J 2
(3490 -285);
DISPLAY 0.680851 (3490 -285);
PAINT MONO (3490 -285);
FORCEPROP 0 LAST $SEC 1
J 0
(3625 -25);
DISPLAY 0.680851 (3625 -25);
PAINT MONO (3625 -25);
DISPLAY INVISIBLE (3625 -25);
FORCEPROP 0 LAST CDS_SEC 1
J 0
(3625 -25);
DISPLAY 0.680851 (3625 -25);
DISPLAY INVISIBLE (3625 -25);
FORCEADD UNIVERSAL_POWER..1
(2775 3025);
FORCEPROP 3 LASTPIN (2775 2975) SIG_NAME P1V0_AUX\g
J 0
(2785 2985);
DISPLAY 0.659574 (2785 2985);
PAINT MONO (2785 2985);
DISPLAY INVISIBLE (2785 2985);
FORCEPROP 1 LAST HDL_POWER P1V0_AUX
J 1
(2775 3075);
DISPLAY 0.702128 (2775 3075);
PAINT GREEN (2775 3075);
FORCEPROP 2 LAST CDS_LIB logical_power
J 0
(2775 3025);
DISPLAY INVISIBLE (2775 3025);
FORCEPROP 1 LAST PATH I90
J 0
(2825 3050);
DISPLAY 0.872340 (2825 3050);
PAINT AQUA (2825 3050);
DISPLAY INVISIBLE (2825 3050);
FORCEADD UNIVERSAL_POWER..1
(2775 3775);
FORCEPROP 3 LASTPIN (2775 3725) SIG_NAME P1V0_AUX\g
J 0
(2785 3735);
DISPLAY 0.659574 (2785 3735);
PAINT MONO (2785 3735);
DISPLAY INVISIBLE (2785 3735);
FORCEPROP 1 LAST HDL_POWER P1V0_AUX
J 1
(2775 3825);
DISPLAY 0.702128 (2775 3825);
PAINT GREEN (2775 3825);
FORCEPROP 2 LAST CDS_LIB logical_power
J 0
(2775 3775);
DISPLAY INVISIBLE (2775 3775);
FORCEPROP 1 LAST PATH I91
J 0
(2825 3800);
DISPLAY 0.872340 (2825 3800);
PAINT AQUA (2825 3800);
DISPLAY INVISIBLE (2825 3800);
FORCEADD Q_RES..1
(3350 2875);
FORCEPROP 1 LAST PART_NUMBER CS00002JB13
J 0
(3300 2975);
DISPLAY 0.510638 (3300 2975);
PAINT WHITE (3300 2975);
FORCEPROP 1 LAST VALUE 0
J 2
(3575 2875);
DISPLAY 0.510638 (3575 2875);
PAINT SKYBLUE (3575 2875);
FORCEPROP 1 LAST TOLERANCE 5%
J 0
(3725 2800);
DISPLAY 0.510638 (3725 2800);
PAINT SKYBLUE (3725 2800);
FORCEPROP 1 LAST WATTAGE 1/16W
J 2
(3175 2800);
DISPLAY 0.510638 (3175 2800);
PAINT SKYBLUE (3175 2800);
FORCEPROP 1 LAST MATERIAL CHIP
J 0
(3200 2800);
DISPLAY 0.510638 (3200 2800);
PAINT SKYBLUE (3200 2800);
FORCEPROP 1 LAST PACK_TYPE 0402LF
J 0
(3425 2800);
DISPLAY 0.510638 (3425 2800);
PAINT SKYBLUE (3425 2800);
FORCEPROP 2 LAST CDS_LIB pure_quanta
J 0
(3350 2875);
DISPLAY INVISIBLE (3350 2875);
FORCEPROP 1 LAST PATH I92
J 0
(3300 3025);
DISPLAY 0.978723 (3300 3025);
PAINT WHITE (3300 3025);
DISPLAY INVISIBLE (3300 3025);
FORCEPROP 1 LAST LOCATION R281
J 0
(3025 2875);
DISPLAY 0.702128 (3025 2875);
PAINT YELLOW (3025 2875);
FORCEPROP 1 LASTPIN (3250 2875) $PN 1
J 0
(3262 2887);
DISPLAY 0.808511 (3262 2887);
PAINT WHITE (3262 2887);
FORCEPROP 1 LASTPIN (3450 2875) $PN 2
J 0
(3412 2887);
DISPLAY 0.808511 (3412 2887);
PAINT WHITE (3412 2887);
FORCEPROP 0 LAST $SEC 1
J 0
(3300 3025);
DISPLAY 0.680851 (3300 3025);
PAINT MONO (3300 3025);
DISPLAY INVISIBLE (3300 3025);
FORCEPROP 0 LAST CDS_SEC 1
J 0
(3625 2925);
DISPLAY 0.680851 (3625 2925);
DISPLAY INVISIBLE (3625 2925);
FORCEADD UNIVERSAL_POWER..1
(2975 3425);
FORCEPROP 3 LASTPIN (2975 3375) SIG_NAME P1V2_AUX\g
J 0
(2985 3385);
DISPLAY 0.659574 (2985 3385);
PAINT MONO (2985 3385);
DISPLAY INVISIBLE (2985 3385);
FORCEPROP 1 LAST HDL_POWER P1V2_AUX
J 1
(2975 3475);
DISPLAY 0.702128 (2975 3475);
PAINT GREEN (2975 3475);
FORCEPROP 2 LAST CDS_LIB logical_power
J 0
(2975 3425);
DISPLAY INVISIBLE (2975 3425);
FORCEPROP 1 LAST PATH I93
J 0
(3025 3450);
DISPLAY 0.872340 (3025 3450);
PAINT AQUA (3025 3450);
DISPLAY INVISIBLE (3025 3450);
FORCEADD Q_RES..1
(3350 3175);
FORCEPROP 1 LAST TOLERANCE 5%
J 0
(3850 3275);
DISPLAY 0.510638 (3850 3275);
PAINT SKYBLUE (3850 3275);
FORCEPROP 1 LAST VALUE 0
J 2
(3550 3175);
DISPLAY 0.510638 (3550 3175);
PAINT SKYBLUE (3550 3175);
FORCEPROP 1 LAST MATERIAL EMPTY
J 0
(3625 3175);
DISPLAY 0.510638 (3625 3175);
PAINT RED (3625 3175);
FORCEPROP 1 LAST WATTAGE 1/16W
J 2
(3525 3275);
DISPLAY 0.510638 (3525 3275);
PAINT SKYBLUE (3525 3275);
FORCEPROP 1 LAST PACK_TYPE 0402LF
J 0
(3550 3275);
DISPLAY 0.510638 (3550 3275);
PAINT SKYBLUE (3550 3275);
FORCEPROP 1 LAST PART_NUMBER CS00002JB13
J 0
(3350 3350);
DISPLAY 0.510638 (3350 3350);
PAINT WHITE (3350 3350);
FORCEPROP 2 LAST CDS_LIB pure_quanta
J 0
(3350 3175);
DISPLAY INVISIBLE (3350 3175);
FORCEPROP 1 LAST PATH I94
J 0
(3300 3325);
DISPLAY 0.978723 (3300 3325);
PAINT WHITE (3300 3325);
DISPLAY INVISIBLE (3300 3325);
FORCEPROP 1 LAST LOCATION R280
J 0
(3025 3175);
DISPLAY 0.702128 (3025 3175);
PAINT YELLOW (3025 3175);
FORCEPROP 1 LASTPIN (3250 3175) $PN 1
J 0
(3262 3187);
DISPLAY 0.808511 (3262 3187);
PAINT WHITE (3262 3187);
FORCEPROP 1 LASTPIN (3450 3175) $PN 2
J 0
(3412 3187);
DISPLAY 0.808511 (3412 3187);
PAINT WHITE (3412 3187);
FORCEPROP 0 LAST $SEC 1
J 0
(3350 3400);
DISPLAY 0.680851 (3350 3400);
PAINT MONO (3350 3400);
DISPLAY INVISIBLE (3350 3400);
FORCEPROP 0 LAST CDS_SEC 1
J 0
(3350 3400);
DISPLAY 0.680851 (3350 3400);
DISPLAY INVISIBLE (3350 3400);
FORCEADD Q_RES..1
(3350 3625);
FORCEPROP 1 LAST VALUE 0
J 2
(3550 3625);
DISPLAY 0.510638 (3550 3625);
PAINT SKYBLUE (3550 3625);
FORCEPROP 1 LAST TOLERANCE 5%
J 0
(3850 3550);
DISPLAY 0.510638 (3850 3550);
PAINT SKYBLUE (3850 3550);
FORCEPROP 1 LAST WATTAGE 1/16W
J 2
(3275 3550);
DISPLAY 0.510638 (3275 3550);
PAINT SKYBLUE (3275 3550);
FORCEPROP 1 LAST MATERIAL CHIP
J 0
(3300 3550);
DISPLAY 0.510638 (3300 3550);
PAINT SKYBLUE (3300 3550);
FORCEPROP 1 LAST PACK_TYPE 0402LF
J 0
(3550 3550);
DISPLAY 0.510638 (3550 3550);
PAINT SKYBLUE (3550 3550);
FORCEPROP 1 LAST PART_NUMBER CS00002JB13
J 0
(3300 3725);
DISPLAY 0.510638 (3300 3725);
PAINT WHITE (3300 3725);
FORCEPROP 2 LAST CDS_LIB pure_quanta
J 0
(3350 3625);
DISPLAY INVISIBLE (3350 3625);
FORCEPROP 1 LAST PATH I95
J 0
(3300 3775);
DISPLAY 0.978723 (3300 3775);
PAINT WHITE (3300 3775);
DISPLAY INVISIBLE (3300 3775);
FORCEPROP 1 LAST LOCATION R279
J 0
(3050 3625);
DISPLAY 0.702128 (3050 3625);
PAINT YELLOW (3050 3625);
FORCEPROP 1 LASTPIN (3250 3625) $PN 1
J 0
(3262 3637);
DISPLAY 0.808511 (3262 3637);
PAINT WHITE (3262 3637);
FORCEPROP 1 LASTPIN (3450 3625) $PN 2
J 0
(3412 3637);
DISPLAY 0.808511 (3412 3637);
PAINT WHITE (3412 3637);
FORCEPROP 0 LAST $SEC 1
J 0
(3300 3775);
DISPLAY 0.680851 (3300 3775);
PAINT MONO (3300 3775);
DISPLAY INVISIBLE (3300 3775);
FORCEPROP 0 LAST CDS_SEC 1
J 0
(3625 3675);
DISPLAY 0.680851 (3625 3675);
DISPLAY INVISIBLE (3625 3675);
FORCEADD UNIVERSAL_GND..1
(4100 2825);
FORCEPROP 3 LASTPIN (4100 2875) SIG_NAME GND\g
J 0
(4110 2885);
DISPLAY 0.659574 (4110 2885);
PAINT MONO (4110 2885);
DISPLAY INVISIBLE (4110 2885);
FORCEPROP 2 LAST CDS_LIB logical_power
J 0
(4100 2825);
DISPLAY INVISIBLE (4100 2825);
FORCEPROP 1 LAST HDL_POWER GND
J 1
(4125 2750);
DISPLAY 0.702128 (4125 2750);
PAINT GREEN (4125 2750);
DISPLAY INVISIBLE (4125 2750);
FORCEPROP 1 LAST PATH I96
J 0
(4175 2825);
DISPLAY 0.872340 (4175 2825);
PAINT AQUA (4175 2825);
DISPLAY INVISIBLE (4175 2825);
FORCEADD Q_CAP..1
(4100 3025);
FORCEPROP 1 LAST VALUE 0.1UF
J 0
(4150 3075);
DISPLAY 0.510638 (4150 3075);
PAINT SKYBLUE (4150 3075);
FORCEPROP 1 LAST VOLTAGE 25V
J 0
(4150 3025);
DISPLAY 0.510638 (4150 3025);
PAINT SKYBLUE (4150 3025);
FORCEPROP 1 LAST PART_NUMBER CH4104K1B00
J 0
(4150 2825);
DISPLAY 0.510638 (4150 2825);
PAINT WHITE (4150 2825);
FORCEPROP 1 LAST MATERIAL X7R
J 0
(4150 2925);
DISPLAY 0.510638 (4150 2925);
PAINT SKYBLUE (4150 2925);
FORCEPROP 1 LAST TOLERANCE 10%
J 0
(4150 2975);
DISPLAY 0.510638 (4150 2975);
PAINT SKYBLUE (4150 2975);
FORCEPROP 1 LAST PACK_TYPE 0402
J 0
(4150 2875);
DISPLAY 0.510638 (4150 2875);
PAINT SKYBLUE (4150 2875);
FORCEPROP 2 LAST CDS_LIB pure_quanta
J 0
(4100 3025);
DISPLAY INVISIBLE (4100 3025);
FORCEPROP 1 LAST PATH I97
J 0
(4150 3175);
DISPLAY 0.978723 (4150 3175);
PAINT WHITE (4150 3175);
DISPLAY INVISIBLE (4150 3175);
FORCEPROP 1 LAST LOCATION C140
J 0
(4150 3125);
DISPLAY 0.702128 (4150 3125);
PAINT YELLOW (4150 3125);
FORCEPROP 1 LASTPIN (4100 3125) $PN 1
J 0
(4110 3105);
DISPLAY 0.808511 (4110 3105);
PAINT WHITE (4110 3105);
FORCEPROP 1 LASTPIN (4100 2925) $PN 2
J 0
(4110 2905);
DISPLAY 0.808511 (4110 2905);
PAINT WHITE (4110 2905);
FORCEPROP 0 LAST $SEC 1
J 0
(4150 3175);
DISPLAY 0.680851 (4150 3175);
PAINT MONO (4150 3175);
DISPLAY INVISIBLE (4150 3175);
FORCEPROP 0 LAST CDS_SEC 1
J 0
(4150 3175);
DISPLAY 0.680851 (4150 3175);
DISPLAY INVISIBLE (4150 3175);
FORCEADD Q_CAP..1
(4100 3775);
FORCEPROP 1 LAST VOLTAGE 25V
J 0
(4150 3775);
DISPLAY 0.510638 (4150 3775);
PAINT SKYBLUE (4150 3775);
FORCEPROP 1 LAST PART_NUMBER CH4104K1B00
J 0
(4150 3575);
DISPLAY 0.510638 (4150 3575);
PAINT WHITE (4150 3575);
FORCEPROP 1 LAST MATERIAL X7R
J 0
(4150 3675);
DISPLAY 0.510638 (4150 3675);
PAINT SKYBLUE (4150 3675);
FORCEPROP 1 LAST TOLERANCE 10%
J 0
(4150 3725);
DISPLAY 0.510638 (4150 3725);
PAINT SKYBLUE (4150 3725);
FORCEPROP 1 LAST VALUE 0.1UF
J 0
(4150 3825);
DISPLAY 0.510638 (4150 3825);
PAINT SKYBLUE (4150 3825);
FORCEPROP 1 LAST PACK_TYPE 0402
J 0
(4150 3625);
DISPLAY 0.510638 (4150 3625);
PAINT SKYBLUE (4150 3625);
FORCEPROP 2 LAST CDS_LIB pure_quanta
J 0
(4100 3775);
DISPLAY INVISIBLE (4100 3775);
FORCEPROP 1 LAST PATH I98
J 0
(4150 3925);
DISPLAY 0.978723 (4150 3925);
PAINT WHITE (4150 3925);
DISPLAY INVISIBLE (4150 3925);
FORCEPROP 1 LAST LOCATION C139
J 0
(4150 3875);
DISPLAY 0.702128 (4150 3875);
PAINT YELLOW (4150 3875);
FORCEPROP 1 LASTPIN (4100 3875) $PN 1
J 0
(4110 3855);
DISPLAY 0.808511 (4110 3855);
PAINT WHITE (4110 3855);
FORCEPROP 1 LASTPIN (4100 3675) $PN 2
J 0
(4110 3655);
DISPLAY 0.808511 (4110 3655);
PAINT WHITE (4110 3655);
FORCEPROP 0 LAST $SEC 1
J 0
(4150 3925);
DISPLAY 0.680851 (4150 3925);
PAINT MONO (4150 3925);
DISPLAY INVISIBLE (4150 3925);
FORCEPROP 0 LAST CDS_SEC 1
J 0
(4150 3925);
DISPLAY 0.680851 (4150 3925);
DISPLAY INVISIBLE (4150 3925);
FORCEADD UNIVERSAL_GND..1
(4100 3575);
FORCEPROP 3 LASTPIN (4100 3625) SIG_NAME GND\g
J 0
(4110 3635);
DISPLAY 0.659574 (4110 3635);
PAINT MONO (4110 3635);
DISPLAY INVISIBLE (4110 3635);
FORCEPROP 2 LAST CDS_LIB logical_power
J 0
(4100 3575);
DISPLAY INVISIBLE (4100 3575);
FORCEPROP 1 LAST HDL_POWER GND
J 1
(4125 3500);
DISPLAY 0.702128 (4125 3500);
PAINT GREEN (4125 3500);
DISPLAY INVISIBLE (4125 3500);
FORCEPROP 1 LAST PATH I99
J 0
(4175 3575);
DISPLAY 0.872340 (4175 3575);
PAINT AQUA (4175 3575);
DISPLAY INVISIBLE (4175 3575);
FORCEADD QUANTA_TITLE_BLOCK_C..1
(5100 -2050);
FORCEPROP 0 LAST CDS_CON_LAST_MODIFIED Fri Aug 25 17:25:38 2023
J 0
(3215 -2035);
DISPLAY INVISIBLE (3215 -2035);
FORCEPROP 2 LAST Q_DEPT 
J 1
(1337 -2001);
DISPLAY 1.957447 (1337 -2001);
PAINT GREEN (1337 -2001);
FORCEPROP 1 LAST CUSTOM_TXT_CDS <CON_LAST_MODIFIED>
J 0
(3215 -2035);
DISPLAY 0.978723 (3215 -2035);
FORCEPROP 2 LAST CUSTOM_TXT_CDS <XR_PAGE_TITLE>
J 0
(-2790 3200);
DISPLAY 0.638298 (-2790 3200);
PAINT PINK (-2790 3200);
DISPLAY INVISIBLE (-2790 3200);
FORCEPROP 1 LAST CUSTOM_TXT_CDS <NAME_2>
J 0
(1925 -2000);
FORCEPROP 1 LAST CUSTOM_TXT_CDS <NAME_1>
J 0
(1925 -1875);
FORCEPROP 1 LAST CUSTOM_TXT_CDS <Q_NUMBER>
J 0
(3697 -1947);
DISPLAY 1.212766 (3697 -1947);
FORCEPROP 1 LAST CUSTOM_TXT_CDS <Q_PROJ>
J 0
(2718 -1948);
DISPLAY 1.212766 (2718 -1948);
FORCEPROP 1 LAST CUSTOM_TXT_CDS <Q_REV>
J 0
(4916 -1947);
DISPLAY 1.212766 (4916 -1947);
FORCEPROP 1 LAST CUSTOM_TXT_CDS <CON_PAGE_NUM> OF <CON_TOTAL_PAGES>
J 0
(4654 -2032);
DISPLAY 0.978723 (4654 -2032);
FORCEPROP 1 LAST Q_TITLE BMC 6
J 0
(-4266 -2024);
DISPLAY 2.446809 (-4266 -2024);
PAINT GREEN (-4266 -2024);
FORCEPROP 1 LAST CDS_LMAN_SYM_OUTLINE -9475,6775,100,-125
J 0
(5100 -2050);
DISPLAY 0.468085 (5100 -2050);
PAINT GREEN (5100 -2050);
DISPLAY INVISIBLE (5100 -2050);
FORCEPROP 2 LAST CDS_LIB pure_quanta
J 0
(5100 -2050);
DISPLAY INVISIBLE (5100 -2050);
FORCEPROP 2 LAST PAGE_BORDER TRUE
J 0
(-2790 3200);
DISPLAY 0.638298 (-2790 3200);
PAINT PINK (-2790 3200);
DISPLAY INVISIBLE (-2790 3200);
FORCEPROP 1 LAST COMMENT_BODY TRUE
J 0
(5112 -2063);
DISPLAY 0.978723 (5112 -2063);
PAINT PEACH (5112 -2063);
DISPLAY INVISIBLE (5112 -2063);
FORCEPROP 2 LAST CDS_XR_PAGE_TITLE CR-17 : @SCM_LIB.SCM(SCH_1):PAGE17
J 0
(-2790 3200);
DISPLAY 0.638298 (-2790 3200);
PAINT PINK (-2790 3200);
DISPLAY INVISIBLE (-2790 3200);
FORCEADD DNS..1
(3500 -175);
PAINT RED (3500 -175);
FORCEPROP 1 LAST COMMENT_BODY TRUE
R 1
J 0
(3575 -400);
DISPLAY 0.872340 (3575 -400);
PAINT PEACH (3575 -400);
DISPLAY INVISIBLE (3575 -400);
FORCEPROP 2 LAST CDS_LIB mstr_misc
J 0
(3500 -175);
DISPLAY INVISIBLE (3500 -175);
FORCEADD DNS..2
(-150 1050);
PAINT RED (-150 1050);
FORCEPROP 1 LAST COMMENT_BODY TRUE
R 1
J 0
(-75 825);
DISPLAY 0.872340 (-75 825);
PAINT PEACH (-75 825);
DISPLAY INVISIBLE (-75 825);
FORCEPROP 2 LAST CDS_LIB mstr_misc
J 0
(-150 1050);
DISPLAY INVISIBLE (-150 1050);
FORCEADD DNS..1
(-3525 -1300);
PAINT RED (-3525 -1300);
FORCEPROP 2 LAST CDS_LIB mstr_misc
J 0
(-3525 -1300);
DISPLAY INVISIBLE (-3525 -1300);
FORCEPROP 1 LAST COMMENT_BODY TRUE
R 1
J 0
(-3450 -1525);
DISPLAY 0.872340 (-3450 -1525);
PAINT PEACH (-3450 -1525);
DISPLAY INVISIBLE (-3450 -1525);
FORCEADD DNS..1
(-875 1800);
PAINT RED (-875 1800);
FORCEPROP 2 LAST CDS_LIB mstr_misc
J 0
(-875 1800);
DISPLAY INVISIBLE (-875 1800);
FORCEPROP 1 LAST COMMENT_BODY TRUE
R 1
J 0
(-800 1575);
DISPLAY 0.872340 (-800 1575);
PAINT PEACH (-800 1575);
DISPLAY INVISIBLE (-800 1575);
FORCEADD CAD_NOTE..1
(-100 -1550);
FORCEPROP 0 LAST L2 ADC0-ADC7 (0.9V-2.7V)
J 0
(-225 -1750);
DISPLAY 0.808511 (-225 -1750);
PAINT WHITE (-225 -1750);
FORCEPROP 0 LAST L1 ETERNAL REFERENCE VOLRAGE FOR
J 0
(-225 -1675);
DISPLAY 0.808511 (-225 -1675);
PAINT WHITE (-225 -1675);
FORCEPROP 2 LAST CDS_LIB logical_power
J 0
(-100 -1550);
DISPLAY INVISIBLE (-100 -1550);
FORCEPROP 1 LAST COMMENT_BODY TRUE
J 0
(-75 -1450);
DISPLAY 0.978723 (-75 -1450);
PAINT PEACH (-75 -1450);
DISPLAY INVISIBLE (-75 -1450);
FORCEADD DNS..2
(3300 -1425);
PAINT RED (3300 -1425);
FORCEPROP 2 LAST CDS_LIB mstr_misc
J 0
(3300 -1425);
DISPLAY INVISIBLE (3300 -1425);
FORCEPROP 1 LAST COMMENT_BODY TRUE
R 1
J 0
(3375 -1650);
DISPLAY 0.872340 (3375 -1650);
PAINT PEACH (3375 -1650);
DISPLAY INVISIBLE (3375 -1650);
FORCEADD DNS..2
(2200 -1400);
PAINT RED (2200 -1400);
FORCEPROP 2 LAST CDS_LIB mstr_misc
J 0
(2200 -1400);
DISPLAY INVISIBLE (2200 -1400);
FORCEPROP 1 LAST COMMENT_BODY TRUE
R 1
J 0
(2275 -1625);
DISPLAY 0.872340 (2275 -1625);
PAINT PEACH (2275 -1625);
DISPLAY INVISIBLE (2275 -1625);
FORCEADD DNS..1
(3325 3200);
PAINT RED (3325 3200);
FORCEPROP 2 LAST CDS_LIB mstr_misc
J 0
(3325 3200);
DISPLAY INVISIBLE (3325 3200);
FORCEPROP 1 LAST COMMENT_BODY TRUE
R 1
J 0
(3400 2975);
DISPLAY 0.872340 (3400 2975);
PAINT PEACH (3400 2975);
DISPLAY INVISIBLE (3400 2975);
FORCEADD DNS..1
(3325 3975);
PAINT RED (3325 3975);
FORCEPROP 2 LAST CDS_LIB mstr_misc
J 0
(3325 3975);
DISPLAY INVISIBLE (3325 3975);
FORCEPROP 1 LAST COMMENT_BODY TRUE
R 1
J 0
(3400 3750);
DISPLAY 0.872340 (3400 3750);
PAINT PEACH (3400 3750);
DISPLAY INVISIBLE (3400 3750);
FORCEADD DNS..1
(-1225 -1575);
PAINT RED (-1225 -1575);
FORCEPROP 2 LAST CDS_LIB mstr_misc
J 0
(-1225 -1575);
DISPLAY INVISIBLE (-1225 -1575);
FORCEPROP 1 LAST COMMENT_BODY TRUE
R 1
J 0
(-1150 -1800);
DISPLAY 0.872340 (-1150 -1800);
PAINT PEACH (-1150 -1800);
DISPLAY INVISIBLE (-1150 -1800);
FORCEADD DNS..1
(-3525 -1575);
PAINT RED (-3525 -1575);
FORCEPROP 2 LAST CDS_LIB mstr_misc
J 0
(-3525 -1575);
DISPLAY INVISIBLE (-3525 -1575);
FORCEPROP 1 LAST COMMENT_BODY TRUE
R 1
J 0
(-3450 -1800);
DISPLAY 0.872340 (-3450 -1800);
PAINT PEACH (-3450 -1800);
DISPLAY INVISIBLE (-3450 -1800);
FORCEADD CAD_NOTE..1
(-2775 -1650);
FORCEPROP 0 LAST L2 ADC8-ADC15 (0.9V-2.7V)
J 0
(-2900 -1850);
DISPLAY 0.808511 (-2900 -1850);
PAINT WHITE (-2900 -1850);
FORCEPROP 0 LAST L1 ETERNAL REFERENCE VOLRAGE FOR
J 0
(-2900 -1775);
DISPLAY 0.808511 (-2900 -1775);
PAINT WHITE (-2900 -1775);
FORCEPROP 2 LAST CDS_LIB logical_power
J 0
(-2775 -1650);
DISPLAY INVISIBLE (-2775 -1650);
FORCEPROP 1 LAST COMMENT_BODY TRUE
J 0
(-2750 -1550);
DISPLAY 0.978723 (-2750 -1550);
PAINT PEACH (-2750 -1550);
DISPLAY INVISIBLE (-2750 -1550);
FORCEADD CAD_NOTE..1
(1700 925);
FORCEPROP 0 LAST L1 PLACE CLOSE TO BMC PIN W15
J 0
(1575 800);
DISPLAY 0.808511 (1575 800);
PAINT WHITE (1575 800);
FORCEPROP 2 LAST CDS_LIB logical_power
J 0
(1700 925);
DISPLAY INVISIBLE (1700 925);
FORCEPROP 1 LAST COMMENT_BODY TRUE
J 0
(1725 1025);
DISPLAY 0.978723 (1725 1025);
PAINT PEACH (1725 1025);
DISPLAY INVISIBLE (1725 1025);
FORCEADD DNS..1
(-1125 -1025);
PAINT RED (-1125 -1025);
FORCEPROP 2 LAST CDS_LIB mstr_misc
J 0
(-1125 -1025);
DISPLAY INVISIBLE (-1125 -1025);
FORCEPROP 1 LAST COMMENT_BODY TRUE
R 1
J 0
(-1050 -1250);
DISPLAY 0.872340 (-1050 -1250);
PAINT PEACH (-1050 -1250);
DISPLAY INVISIBLE (-1050 -1250);
FORCEADD DNS..1
(4350 825);
PAINT RED (4350 825);
FORCEPROP 2 LAST CDS_LIB mstr_misc
J 0
(4350 825);
DISPLAY INVISIBLE (4350 825);
FORCEPROP 1 LAST COMMENT_BODY TRUE
R 1
J 0
(4425 600);
DISPLAY 0.872340 (4425 600);
PAINT PEACH (4425 600);
DISPLAY INVISIBLE (4425 600);
FORCEADD DNS..1
(1725 -425);
PAINT RED (1725 -425);
FORCEPROP 2 LAST CDS_LIB mstr_misc
J 0
(1725 -425);
DISPLAY INVISIBLE (1725 -425);
FORCEPROP 1 LAST COMMENT_BODY TRUE
R 1
J 0
(1800 -650);
DISPLAY 0.872340 (1800 -650);
PAINT PEACH (1800 -650);
DISPLAY INVISIBLE (1800 -650);
FORCEADD DNS..1
(4350 -25);
PAINT RED (4350 -25);
FORCEPROP 1 LAST COMMENT_BODY TRUE
R 1
J 0
(4425 -250);
DISPLAY 0.872340 (4425 -250);
PAINT PEACH (4425 -250);
DISPLAY INVISIBLE (4425 -250);
FORCEPROP 2 LAST CDS_LIB mstr_misc
J 0
(4350 -25);
DISPLAY INVISIBLE (4350 -25);
WIRE 16 -1 (2825 -400)(2825 -500);
WIRE 16 -1 (4925 -625)(4925 175);
WIRE 16 -1 (4350 -625)(4925 -625);
WIRE 16 -1 (-450 700)(-450 675);
WIRE 16 -1 (-3950 -1225)(-3950 -1325);
WIRE 16 -1 (-3850 -950)(-3850 -1050);
WIRE 16 -1 (-1350 2050)(-1350 2250);
WIRE 16 -1 (-1075 2050)(-1350 2050);
WIRE 16 -1 (-1700 3200)(-1700 3175);
WIRE 16 -1 (1450 2150)(1450 2125);
WIRE 16 -1 (3750 1150)(3750 1275);
WIRE 16 -1 (3750 1150)(4350 1150);
WIRE 16 -1 (3750 1025)(3750 1150);
WIRE 16 -1 (-1775 -100)(-1775 -125);
WIRE 16 -1 (2975 3175)(2975 3375);
WIRE 16 -1 (3250 3175)(2975 3175);
WIRE 16 -1 (2775 3725)(2775 3625);
WIRE 16 -1 (2775 2975)(2775 2875);
WIRE 16 -1 (-3950 -1500)(-3950 -1600);
WIRE 16 -1 (-1650 -1500)(-1650 -1600);
WIRE 16 -1 (-1550 -950)(-1550 -1050);
WIRE 16 -1 (-1650 -1225)(-1650 -1325);
WIRE 16 -1 (2825 2200)(2825 2175);
WIRE 16 -1 (-1700 950)(-1700 925);
WIRE 16 -1 (-475 1200)(-475 1050);
WIRE 16 -1 (-1725 4075)(-1725 4050);
WIRE 16 -1 (4550 3925)(4550 4100);
WIRE 16 -1 (4550 3925)(4100 3925);
WIRE 16 -1 (2925 3925)(2925 4125);
WIRE 16 -1 (3250 3925)(2925 3925);
WIRE 16 -1 (4550 3175)(4550 3350);
WIRE 16 -1 (4550 3175)(4100 3175);
WIRE 16 -1 (1600 500)(1600 425);
WIRE 16 -1 (-1450 1875)(-1450 1775);
WIRE 16 -1 (225 2050)(225 2250);
WIRE 16 -1 (225 2050)(100 2050);
WIRE 16 -1 (-450 -50)(-450 -75);
WIRE 16 -1 (1725 -500)(1725 -650);
WIRE 16 -1 (2050 150)(2050 50);
WIRE 16 -1 (4100 3675)(4100 3625);
WIRE 16 -1 (4100 2925)(4100 2875);
WIRE 16 -1 (-2725 -1475)(-2725 -1450);
WIRE 16 -1 (-425 -1475)(-425 -1450);
WIRE 16 -1 (2200 -1475)(2200 -1550);
WIRE 16 -1 (3300 -1500)(3300 -1575);
WIRE 16 -1 (2825 -1600)(2825 -1275);
WIRE 16 -1 (-2300 -275)(-2300 -575);
WIRE 16 -1 (-2300 75)(-2300 -275);
WIRE 16 -1 (-2550 -275)(-2300 -275);
WIRE 16 -1 (2150 1725)(2150 1775);
WIRE 16 -1 (3525 1775)(3525 1825);
WIRE 16 -1 (-1075 -525)(-1075 -475);
WIRE 16 -1 (250 -475)(250 -425);
WIRE 16 -1 (-1000 525)(-1000 575);
WIRE 16 -1 (300 650)(300 700);
WIRE 16 -1 (-75 1625)(-75 1650);
WIRE 16 -1 (-1000 2775)(-1000 2825);
WIRE 16 -1 (-1025 3650)(-1025 3700);
WIRE 16 -1 (125 3900)(125 3825);
WIRE 16 -1 (300 3900)(125 3900);
WIRE 16 -1 (125 3900)(125 4025);
WIRE 16 -1 (75 3300)(75 3225);
WIRE 16 -1 (75 3300)(75 3425);
WIRE 16 -1 (250 3300)(75 3300);
WIRE 16 -1 (-3900 -275)(-3900 -600);
WIRE 16 -1 (-3600 -275)(-3900 -275);
WIRE 16 -1 (-3900 -225)(-3900 -275);
WIRE 16 -1 (1650 100)(1650 150);
WIRE 16 3135 (-1925 -625)(-1925 250);
WIRE 16 3135 (-1925 -625)(1200 -625);
WIRE 16 3135 (1200 250)(-1925 250);
WIRE 16 3135 (1200 250)(1200 -625);
WIRE 16 -1 (-3600 -225)(-3900 -225);
WIRE 16 -1 (-3900 -175)(-3900 -225);
WIRE 16 -1 (-3600 -175)(-3900 -175);
WIRE 16 -1 (-3900 -125)(-3900 -175);
WIRE 16 -1 (-3600 -125)(-3900 -125);
WIRE 16 -1 (-3900 -75)(-3900 -125);
WIRE 16 -1 (-3600 -75)(-3900 -75);
WIRE 16 -1 (-3900 -25)(-3900 -75);
WIRE 16 -1 (-3600 -25)(-3900 -25);
WIRE 16 -1 (-3900 25)(-3900 -25);
WIRE 16 -1 (-3600 25)(-3900 25);
WIRE 16 -1 (-3900 75)(-3900 25);
WIRE 16 -1 (-3600 75)(-3900 75);
WIRE 16 -1 (-3900 125)(-3900 75);
WIRE 16 -1 (-3600 125)(-3900 125);
WIRE 16 -1 (-3900 175)(-3900 125);
WIRE 16 -1 (-3600 175)(-3900 175);
WIRE 16 -1 (-3900 225)(-3900 175);
WIRE 16 -1 (-3600 225)(-3900 225);
WIRE 16 -1 (-3900 275)(-3900 225);
WIRE 16 -1 (-3600 275)(-3900 275);
WIRE 16 -1 (-3900 325)(-3900 275);
WIRE 16 -1 (-3600 325)(-3900 325);
WIRE 16 -1 (-3900 375)(-3900 325);
WIRE 16 -1 (-3600 375)(-3900 375);
WIRE 16 -1 (-3900 425)(-3900 375);
WIRE 16 -1 (-3600 425)(-3900 425);
WIRE 16 -1 (-3900 475)(-3900 425);
WIRE 16 -1 (-3600 475)(-3900 475);
WIRE 16 -1 (-3900 525)(-3900 475);
WIRE 16 -1 (-3600 525)(-3900 525);
WIRE 16 -1 (-3900 575)(-3900 525);
WIRE 16 -1 (-3600 575)(-3900 575);
WIRE 16 -1 (-3900 625)(-3900 575);
WIRE 16 -1 (-3600 625)(-3900 625);
WIRE 16 -1 (-3900 675)(-3900 625);
WIRE 16 -1 (-3600 675)(-3900 675);
WIRE 16 -1 (-3900 725)(-3900 675);
WIRE 16 -1 (-3600 725)(-3900 725);
WIRE 16 -1 (-3900 775)(-3900 725);
WIRE 16 -1 (-3600 775)(-3900 775);
WIRE 16 -1 (-3900 825)(-3900 775);
WIRE 16 -1 (-3600 825)(-3900 825);
WIRE 16 -1 (-3900 875)(-3900 825);
WIRE 16 -1 (-3600 875)(-3900 875);
WIRE 16 -1 (-3900 925)(-3900 875);
WIRE 16 -1 (-3600 925)(-3900 925);
WIRE 16 -1 (-3900 975)(-3900 925);
WIRE 16 -1 (-3600 975)(-3900 975);
WIRE 16 -1 (-3900 1025)(-3900 975);
WIRE 16 -1 (-3600 1025)(-3900 1025);
WIRE 16 -1 (-3900 1075)(-3900 1025);
WIRE 16 -1 (-3600 1075)(-3900 1075);
WIRE 16 -1 (-3900 1125)(-3900 1075);
WIRE 16 -1 (-3600 1125)(-3900 1125);
WIRE 16 -1 (-3900 1175)(-3900 1125);
WIRE 16 -1 (-3600 1175)(-3900 1175);
WIRE 16 -1 (-3900 1225)(-3900 1175);
WIRE 16 -1 (-3600 1225)(-3900 1225);
WIRE 16 -1 (-3900 1275)(-3900 1225);
WIRE 16 -1 (-3600 1275)(-3900 1275);
WIRE 16 -1 (-3900 1325)(-3900 1275);
WIRE 16 -1 (-3600 1325)(-3900 1325);
WIRE 16 -1 (-3900 1375)(-3900 1325);
WIRE 16 -1 (-3600 1375)(-3900 1375);
WIRE 16 -1 (-3900 1425)(-3900 1375);
WIRE 16 -1 (-3600 1425)(-3900 1425);
WIRE 16 -1 (-3900 1475)(-3900 1425);
WIRE 16 -1 (-3600 1475)(-3900 1475);
WIRE 16 -1 (-3900 1525)(-3900 1475);
WIRE 16 -1 (-3600 1525)(-3900 1525);
WIRE 16 -1 (-3900 1575)(-3900 1525);
WIRE 16 -1 (-3600 1575)(-3900 1575);
WIRE 16 -1 (-3900 1625)(-3900 1575);
WIRE 16 -1 (-3600 1625)(-3900 1625);
WIRE 16 -1 (-3900 1675)(-3900 1625);
WIRE 16 -1 (-3600 1675)(-3900 1675);
WIRE 16 -1 (-3900 1725)(-3900 1675);
WIRE 16 -1 (-3600 1725)(-3900 1725);
WIRE 16 -1 (-3900 1775)(-3900 1725);
WIRE 16 -1 (-3600 1775)(-3900 1775);
WIRE 16 -1 (-3900 1825)(-3900 1775);
WIRE 16 -1 (-3600 1825)(-3900 1825);
WIRE 16 -1 (-3900 1875)(-3900 1825);
WIRE 16 -1 (-3600 1875)(-3900 1875);
WIRE 16 -1 (-3900 1925)(-3900 1875);
WIRE 16 -1 (-3600 1925)(-3900 1925);
WIRE 16 -1 (-3900 1975)(-3900 1925);
WIRE 16 -1 (-3600 1975)(-3900 1975);
WIRE 16 -1 (-3900 2025)(-3900 1975);
WIRE 16 -1 (-3600 2025)(-3900 2025);
WIRE 16 -1 (-3900 2075)(-3900 2025);
WIRE 16 -1 (-3600 2075)(-3900 2075);
WIRE 16 -1 (-3900 2125)(-3900 2075);
WIRE 16 -1 (-3600 2125)(-3900 2125);
WIRE 16 -1 (-3900 2175)(-3900 2125);
WIRE 16 -1 (-3600 2175)(-3900 2175);
WIRE 16 -1 (-3900 2225)(-3900 2175);
WIRE 16 -1 (-3600 2225)(-3900 2225);
WIRE 16 -1 (-3900 2275)(-3900 2225);
WIRE 16 -1 (-3600 2275)(-3900 2275);
WIRE 16 -1 (-3900 2325)(-3900 2275);
WIRE 16 -1 (-3600 2325)(-3900 2325);
WIRE 16 -1 (-3900 2375)(-3900 2325);
WIRE 16 -1 (-3600 2375)(-3900 2375);
WIRE 16 -1 (-3900 2425)(-3900 2375);
WIRE 16 -1 (-3600 2425)(-3900 2425);
WIRE 16 -1 (-3900 2475)(-3900 2425);
WIRE 16 -1 (-3600 2475)(-3900 2475);
WIRE 16 -1 (-3900 2525)(-3900 2475);
WIRE 16 -1 (-3600 2525)(-3900 2525);
WIRE 16 -1 (-3900 2575)(-3900 2525);
WIRE 16 -1 (-3600 2575)(-3900 2575);
WIRE 16 -1 (-3900 2625)(-3900 2575);
WIRE 16 -1 (-3600 2625)(-3900 2625);
WIRE 16 -1 (-3900 2675)(-3900 2625);
WIRE 16 -1 (-3600 2675)(-3900 2675);
WIRE 16 -1 (-3900 2725)(-3900 2675);
WIRE 16 -1 (-3600 2725)(-3900 2725);
WIRE 16 -1 (-3900 2775)(-3900 2725);
WIRE 16 -1 (-3600 2775)(-3900 2775);
WIRE 16 -1 (-3900 2825)(-3900 2775);
WIRE 16 -1 (-3600 2825)(-3900 2825);
WIRE 16 -1 (-3900 2875)(-3900 2825);
WIRE 16 -1 (-3600 2875)(-3900 2875);
WIRE 16 -1 (-3900 2925)(-3900 2875);
WIRE 16 -1 (-3600 2925)(-3900 2925);
WIRE 16 -1 (-3900 2975)(-3900 2925);
WIRE 16 -1 (-3600 2975)(-3900 2975);
WIRE 16 -1 (-3900 3025)(-3900 2975);
WIRE 16 -1 (-3600 3025)(-3900 3025);
WIRE 16 -1 (-3900 3075)(-3900 3025);
WIRE 16 -1 (-3600 3075)(-3900 3075);
WIRE 16 -1 (-3900 3125)(-3900 3075);
WIRE 16 -1 (-3600 3125)(-3900 3125);
WIRE 16 -1 (-3900 3175)(-3900 3125);
WIRE 16 -1 (-3600 3175)(-3900 3175);
WIRE 16 -1 (-3900 3225)(-3900 3175);
WIRE 16 -1 (-3600 3225)(-3900 3225);
WIRE 16 -1 (-3900 3275)(-3900 3225);
WIRE 16 -1 (-3600 3275)(-3900 3275);
WIRE 16 -1 (-3900 3325)(-3900 3275);
WIRE 16 -1 (-3600 3325)(-3900 3325);
WIRE 16 -1 (-3900 3375)(-3900 3325);
WIRE 16 -1 (-3600 3375)(-3900 3375);
WIRE 16 -1 (-3900 3425)(-3900 3375);
WIRE 16 -1 (-3600 3425)(-3900 3425);
WIRE 16 -1 (-3900 3475)(-3900 3425);
WIRE 16 -1 (-3600 3475)(-3900 3475);
WIRE 16 -1 (-3900 3525)(-3900 3475);
WIRE 16 -1 (-3600 3525)(-3900 3525);
WIRE 16 -1 (-3900 3575)(-3900 3525);
WIRE 16 -1 (-3600 3575)(-3900 3575);
WIRE 16 -1 (-3900 3625)(-3900 3575);
WIRE 16 -1 (-3600 3625)(-3900 3625);
WIRE 16 -1 (75 3425)(675 3425);
WIRE 16 -1 (125 4025)(725 4025);
WIRE 16 -1 (-2300 75)(-2550 75);
WIRE 16 -1 (-2300 125)(-2550 125);
WIRE 16 -1 (-2300 125)(-2300 75);
WIRE 16 -1 (-2300 175)(-2550 175);
WIRE 16 -1 (-2300 175)(-2300 125);
WIRE 16 -1 (-2300 225)(-2550 225);
WIRE 16 -1 (-2300 225)(-2300 175);
WIRE 16 -1 (-2300 275)(-2550 275);
WIRE 16 -1 (-2300 275)(-2300 225);
WIRE 16 -1 (-2300 325)(-2550 325);
WIRE 16 -1 (-2300 325)(-2300 275);
WIRE 16 -1 (-2300 375)(-2550 375);
WIRE 16 -1 (-2300 375)(-2300 325);
WIRE 16 -1 (-2300 425)(-2550 425);
WIRE 16 -1 (-2300 425)(-2300 375);
WIRE 16 -1 (-2300 475)(-2550 475);
WIRE 16 -1 (-2300 475)(-2300 425);
WIRE 16 -1 (-2300 525)(-2300 475);
WIRE 16 -1 (-2300 525)(-2550 525);
WIRE 16 -1 (-2300 575)(-2550 575);
WIRE 16 -1 (-2300 575)(-2300 525);
WIRE 16 -1 (-2300 625)(-2550 625);
WIRE 16 -1 (-2300 625)(-2300 575);
WIRE 16 -1 (-2300 675)(-2550 675);
WIRE 16 -1 (-2300 675)(-2300 625);
WIRE 16 -1 (-2300 725)(-2550 725);
WIRE 16 -1 (-2300 725)(-2300 675);
WIRE 16 -1 (-2300 775)(-2550 775);
WIRE 16 -1 (-2300 775)(-2300 725);
WIRE 16 -1 (-2300 825)(-2550 825);
WIRE 16 -1 (-2300 825)(-2300 775);
WIRE 16 -1 (-2300 875)(-2550 875);
WIRE 16 -1 (-2300 875)(-2300 825);
WIRE 16 -1 (-2300 925)(-2550 925);
WIRE 16 -1 (-2300 925)(-2300 875);
WIRE 16 -1 (-2300 975)(-2550 975);
WIRE 16 -1 (-2300 975)(-2300 925);
WIRE 16 -1 (-2300 1025)(-2300 975);
WIRE 16 -1 (-2300 1025)(-2550 1025);
WIRE 16 -1 (-2300 1075)(-2550 1075);
WIRE 16 -1 (-2300 1075)(-2300 1025);
WIRE 16 -1 (-2300 1125)(-2550 1125);
WIRE 16 -1 (-2300 1125)(-2300 1075);
WIRE 16 -1 (-2300 1175)(-2550 1175);
WIRE 16 -1 (-2300 1175)(-2300 1125);
WIRE 16 -1 (-2300 1225)(-2550 1225);
WIRE 16 -1 (-2300 1225)(-2300 1175);
WIRE 16 -1 (-2300 1275)(-2550 1275);
WIRE 16 -1 (-2300 1275)(-2300 1225);
WIRE 16 -1 (-2300 1325)(-2550 1325);
WIRE 16 -1 (-2300 1325)(-2300 1275);
WIRE 16 -1 (-2300 1375)(-2550 1375);
WIRE 16 -1 (-2300 1375)(-2300 1325);
WIRE 16 -1 (-2300 1425)(-2550 1425);
WIRE 16 -1 (-2300 1425)(-2300 1375);
WIRE 16 -1 (-2300 1475)(-2550 1475);
WIRE 16 -1 (-2300 1475)(-2300 1425);
WIRE 16 -1 (-2300 1525)(-2550 1525);
WIRE 16 -1 (-2300 1525)(-2300 1475);
WIRE 16 -1 (-2300 1575)(-2300 1525);
WIRE 16 -1 (-2300 1575)(-2550 1575);
WIRE 16 -1 (-2300 1625)(-2550 1625);
WIRE 16 -1 (-2300 1625)(-2300 1575);
WIRE 16 -1 (-2300 1675)(-2550 1675);
WIRE 16 -1 (-2300 1675)(-2300 1625);
WIRE 16 -1 (-2300 1725)(-2550 1725);
WIRE 16 -1 (-2300 1725)(-2300 1675);
WIRE 16 -1 (-2300 1775)(-2550 1775);
WIRE 16 -1 (-2300 1775)(-2300 1725);
WIRE 16 -1 (-2300 1825)(-2550 1825);
WIRE 16 -1 (-2300 1825)(-2300 1775);
WIRE 16 -1 (-2300 1875)(-2550 1875);
WIRE 16 -1 (-2300 1875)(-2300 1825);
WIRE 16 -1 (-2300 1925)(-2550 1925);
WIRE 16 -1 (-2300 1925)(-2300 1875);
WIRE 16 -1 (-2300 1975)(-2550 1975);
WIRE 16 -1 (-2300 1975)(-2300 1925);
WIRE 16 -1 (-2300 2025)(-2550 2025);
WIRE 16 -1 (-2300 2025)(-2300 1975);
WIRE 16 -1 (-2300 2075)(-2300 2025);
WIRE 16 -1 (-2300 2075)(-2550 2075);
WIRE 16 -1 (-2300 2125)(-2550 2125);
WIRE 16 -1 (-2300 2125)(-2300 2075);
WIRE 16 -1 (-2300 2175)(-2550 2175);
WIRE 16 -1 (-2300 2175)(-2300 2125);
WIRE 16 -1 (-2300 2225)(-2550 2225);
WIRE 16 -1 (-2300 2225)(-2300 2175);
WIRE 16 -1 (-2300 2275)(-2550 2275);
WIRE 16 -1 (-2300 2275)(-2300 2225);
WIRE 16 -1 (-2300 2325)(-2550 2325);
WIRE 16 -1 (-2300 2325)(-2300 2275);
WIRE 16 -1 (-2300 2375)(-2550 2375);
WIRE 16 -1 (-2300 2375)(-2300 2325);
WIRE 16 -1 (-2300 2425)(-2550 2425);
WIRE 16 -1 (-2300 2425)(-2300 2375);
WIRE 16 -1 (-2300 2475)(-2550 2475);
WIRE 16 -1 (-2300 2475)(-2300 2425);
WIRE 16 -1 (-2300 2525)(-2550 2525);
WIRE 16 -1 (-2300 2525)(-2300 2475);
WIRE 16 -1 (-2300 2575)(-2300 2525);
WIRE 16 -1 (-2300 2575)(-2550 2575);
WIRE 16 -1 (-2300 2625)(-2550 2625);
WIRE 16 -1 (-2300 2625)(-2300 2575);
WIRE 16 -1 (-2300 2675)(-2550 2675);
WIRE 16 -1 (-2300 2675)(-2300 2625);
WIRE 16 -1 (-2300 2725)(-2550 2725);
WIRE 16 -1 (-2300 2725)(-2300 2675);
WIRE 16 -1 (-2300 2775)(-2550 2775);
WIRE 16 -1 (-2300 2775)(-2300 2725);
WIRE 16 -1 (-2300 2825)(-2550 2825);
WIRE 16 -1 (-2300 2825)(-2300 2775);
WIRE 16 -1 (-2300 2875)(-2550 2875);
WIRE 16 -1 (-2300 2875)(-2300 2825);
WIRE 16 -1 (-2300 2925)(-2550 2925);
WIRE 16 -1 (-2300 2925)(-2300 2875);
WIRE 16 -1 (-2300 2975)(-2550 2975);
WIRE 16 -1 (-2300 2975)(-2300 2925);
WIRE 16 -1 (-2300 3025)(-2550 3025);
WIRE 16 -1 (-2300 3025)(-2300 2975);
WIRE 16 -1 (-2300 3075)(-2300 3025);
WIRE 16 -1 (-2300 3075)(-2550 3075);
WIRE 16 -1 (-2300 3125)(-2550 3125);
WIRE 16 -1 (-2300 3125)(-2300 3075);
WIRE 16 -1 (-2300 3175)(-2550 3175);
WIRE 16 -1 (-2300 3175)(-2300 3125);
WIRE 16 -1 (-2300 3225)(-2550 3225);
WIRE 16 -1 (-2300 3225)(-2300 3175);
WIRE 16 -1 (-2300 3275)(-2550 3275);
WIRE 16 -1 (-2300 3275)(-2300 3225);
WIRE 16 -1 (-2300 3325)(-2550 3325);
WIRE 16 -1 (-2300 3325)(-2300 3275);
WIRE 16 -1 (-2300 3375)(-2550 3375);
WIRE 16 -1 (-2300 3375)(-2300 3325);
WIRE 16 -1 (-2300 3425)(-2550 3425);
WIRE 16 -1 (-2300 3425)(-2300 3375);
WIRE 16 -1 (-2300 3475)(-2550 3475);
WIRE 16 -1 (-2300 3475)(-2300 3425);
WIRE 16 -1 (-2300 3525)(-2550 3525);
WIRE 16 -1 (-2300 3525)(-2300 3475);
WIRE 16 -1 (-2300 3575)(-2550 3575);
WIRE 16 -1 (-2300 3575)(-2300 3525);
WIRE 16 -1 (-2300 3625)(-2300 3575);
WIRE 16 -1 (-2300 3625)(-2550 3625);
WIRE 16 2175 (1300 -1750)(1300 -300);
WIRE 16 -1 (2825 -975)(2825 -825);
WIRE 16 -1 (2825 -700)(2825 -825);
WIRE 16 -1 (1725 -300)(1725 -175);
WIRE 16 -1 (2200 -825)(2825 -825);
WIRE 16 -1 (2200 -1275)(2200 -825);
FORCEPROP 2 LAST SIG_NAME LPC_ESPI_SEL_N
J 0
(2240 -815);
DISPLAY 0.808511 (2240 -815);
WIRE 16 -1 (2200 -825)(2200 -175);
WIRE 16 -1 (2200 -175)(1725 -175);
WIRE 16 -1 (3125 -175)(2200 -175);
WIRE 16 -1 (3300 -175)(3125 -175);
WIRE 16 -1 (3125 925)(3125 -175);
WIRE 16 -1 (3125 925)(3550 925);
WIRE 16 -1 (3450 2875)(3925 2875);
WIRE 16 -1 (3925 2875)(3925 3175);
WIRE 16 -1 (3925 3175)(3450 3175);
WIRE 16 -1 (4100 3175)(3925 3175);
WIRE 16 -1 (4100 3125)(4100 3175);
WIRE 16 -1 (3450 3625)(3925 3625);
WIRE 16 -1 (3925 3925)(3450 3925);
WIRE 16 -1 (3925 3625)(3925 3925);
WIRE 16 -1 (4100 3925)(3925 3925);
WIRE 16 -1 (4100 3875)(4100 3925);
WIRE 16 -1 (-1725 4050)(-1525 4050);
WIRE 16 -1 (-1125 3775)(-1125 3700);
WIRE 16 -1 (-1125 3700)(-1025 3700);
WIRE 16 -1 (-1025 3700)(-925 3700);
WIRE 16 -1 (-925 3775)(-925 3700);
WIRE 16 -1 (-1700 3175)(-1500 3175);
WIRE 16 -1 (-1100 2900)(-1100 2825);
WIRE 16 -1 (-1100 2825)(-1000 2825);
WIRE 16 -1 (-1000 2825)(-900 2825);
WIRE 16 -1 (-900 2900)(-900 2825);
WIRE 16 -1 (-775 1775)(-400 1775);
WIRE 16 -1 (-400 1775)(-400 2050);
WIRE 16 -1 (-400 2050)(-875 2050);
WIRE 16 -1 (-250 2050)(-400 2050);
WIRE 16 -1 (-250 1975)(-250 2050);
WIRE 16 -1 (100 2050)(-250 2050);
WIRE 16 -1 (100 1975)(100 2050);
WIRE 16 -1 (-250 1775)(-250 1650);
WIRE 16 -1 (-250 1650)(-75 1650);
WIRE 16 -1 (-75 1650)(100 1650);
WIRE 16 -1 (100 1775)(100 1650);
WIRE 16 -1 (-975 1775)(-1450 1775);
WIRE 16 -1 (425 775)(425 700);
WIRE 16 -1 (300 700)(425 700);
WIRE 16 -1 (225 700)(300 700);
WIRE 16 -1 (225 775)(225 700);
WIRE 16 -1 (-475 1050)(-225 1050);
WIRE 16 -1 (-1700 925)(-1500 925);
WIRE 16 -1 (-900 650)(-900 575);
WIRE 16 -1 (-1000 575)(-900 575);
WIRE 16 -1 (-1100 575)(-1000 575);
WIRE 16 -1 (-1100 650)(-1100 575);
WIRE 16 -1 (350 -350)(350 -425);
WIRE 16 -1 (250 -425)(350 -425);
WIRE 16 -1 (150 -425)(250 -425);
WIRE 16 -1 (150 -350)(150 -425);
WIRE 16 -1 (-450 -75)(-250 -75);
WIRE 16 -1 (-1775 -125)(-1575 -125);
WIRE 16 -1 (-975 -400)(-975 -475);
WIRE 16 -1 (-1075 -475)(-975 -475);
WIRE 16 -1 (-1175 -475)(-1075 -475);
WIRE 16 -1 (-1175 -400)(-1175 -475);
WIRE 16 -1 (3425 1900)(3425 1825);
WIRE 16 -1 (3425 1825)(3525 1825);
WIRE 16 -1 (3525 1825)(3625 1825);
WIRE 16 -1 (3625 1900)(3625 1825);
WIRE 16 -1 (2825 2175)(3025 2175);
WIRE 16 -1 (1450 2125)(1650 2125);
WIRE 16 -1 (2050 1850)(2050 1775);
WIRE 16 -1 (2050 1775)(2150 1775);
WIRE 16 -1 (2150 1775)(2250 1775);
WIRE 16 -1 (2250 1850)(2250 1775);
WIRE 16 -1 (2225 425)(2050 425);
WIRE 16 -1 (2050 350)(2050 425);
WIRE 16 -1 (1650 350)(1650 425);
WIRE 16 -1 (1650 425)(2050 425);
WIRE 16 -1 (1650 425)(1600 425);
WIRE 16 -1 (-250 -1325)(-250 -1450);
WIRE 16 -1 (-425 -1450)(-250 -1450);
WIRE 16 -1 (-600 -1450)(-425 -1450);
WIRE 16 -1 (-600 -1325)(-600 -1450);
WIRE 16 -1 (-2550 -1325)(-2550 -1450);
WIRE 16 -1 (-2725 -1450)(-2550 -1450);
WIRE 16 -1 (-2900 -1450)(-2725 -1450);
WIRE 16 -1 (-2900 -1325)(-2900 -1450);
WIRE 16 -1 (-1325 -1325)(-1650 -1325);
WIRE 16 -1 (-3625 -1325)(-3950 -1325);
WIRE 16 -1 (-1225 -1050)(-1550 -1050);
WIRE 16 -1 (-3525 -1050)(-3850 -1050);
WIRE 16 -1 (-1325 -1600)(-1650 -1600);
WIRE 16 -1 (-3625 -1600)(-3950 -1600);
WIRE 16 -1 (-450 675)(-225 675);
WIRE 16 -1 (4350 1150)(4350 900);
WIRE 16 -1 (3500 -275)(3500 -625);
WIRE 16 -1 (3500 -625)(4350 -625);
WIRE 16 -1 (4350 -625)(4350 -100);
WIRE 16 -1 (3250 2875)(2775 2875);
WIRE 16 -1 (3250 3625)(2775 3625);
WIRE 16 -1 (3300 -1175)(3025 -1175);
FORCEPROP 2 LAST SIG_NAME LPC_ESPI_SEL_R
J 0
(3115 -1165);
DISPLAY 0.808511 (3115 -1165);
WIRE 16 -1 (3300 -1175)(3300 -1300);
WIRE 16 -1 (3675 -1175)(3300 -1175);
WIRE 16 -1 (3875 -1175)(4625 -1175);
FORCEPROP 2 LAST SIG_NAME LPC_ESPI_SEL
J 0
(4165 -1165);
DISPLAY 0.808511 (4165 -1165);
WIRE 16 -1 (3800 600)(3800 675);
WIRE 16 -1 (3750 600)(3800 600);
WIRE 16 -1 (3750 675)(3750 600);
WIRE 16 -1 (3700 675)(3700 600);
WIRE 16 -1 (3700 600)(3750 600);
WIRE 16 -1 (4350 525)(4350 700);
WIRE 16 -1 (3650 600)(3700 600);
WIRE 16 -1 (3650 675)(3650 600);
WIRE 16 -1 (3650 525)(3650 600);
WIRE 16 -1 (3650 525)(4350 525);
WIRE 16 -1 (3500 25)(3500 325);
WIRE 16 -1 (3650 425)(2425 425);
FORCEPROP 2 LAST SIG_NAME PGPPA_BMC_AUX_L
J 0
(2540 435);
DISPLAY 0.808511 (2540 435);
WIRE 16 -1 (3650 425)(3650 525);
WIRE 16 -1 (3650 325)(3650 425);
WIRE 16 -1 (3500 325)(3650 325);
WIRE 16 -1 (4350 325)(3650 325);
WIRE 16 -1 (4350 100)(4350 325);
WIRE 16 -1 (-1100 3175)(-1300 3175);
FORCEPROP 2 LAST SIG_NAME P1V0_STBY_RC_VCC10A
J 0
(-1235 3185);
DISPLAY 0.808511 (-1235 3185);
WIRE 16 -1 (-1100 3100)(-1100 3175);
WIRE 16 -1 (-900 3100)(-900 3175);
WIRE 16 -1 (-475 3175)(-900 3175);
WIRE 16 -1 (-900 3175)(-1100 3175);
WIRE 16 -1 (725 3225)(1950 3225);
FORCEPROP 2 LAST SIG_NAME A_BMC_ADCVREFN1
J 0
(1440 3235);
DISPLAY 0.808511 (1440 3235);
WIRE 16 -1 (725 3300)(725 3225);
WIRE 16 -1 (900 3300)(725 3300);
WIRE 16 -1 (450 3300)(725 3300);
WIRE 16 -1 (1375 3300)(1100 3300);
WIRE 16 -1 (1375 3300)(1950 3300);
FORCEPROP 2 LAST SIG_NAME A_BMC_ADCVREFP1
J 0
(1440 3310);
DISPLAY 0.808511 (1440 3310);
WIRE 16 -1 (1375 3425)(1375 3300);
WIRE 16 -1 (875 3425)(1375 3425);
WIRE 16 -1 (2050 2125)(1850 2125);
FORCEPROP 2 LAST SIG_NAME P1V0_STBY_DP_VCC10A
J 0
(1915 2135);
DISPLAY 0.808511 (1915 2135);
WIRE 16 -1 (2050 2050)(2050 2125);
WIRE 16 -1 (2250 2050)(2250 2125);
WIRE 16 -1 (2625 2125)(2250 2125);
WIRE 16 -1 (2250 2125)(2050 2125);
WIRE 16 -1 (3425 2175)(3225 2175);
FORCEPROP 2 LAST SIG_NAME P1V8_STBY_DP_VCC18A
J 0
(3265 2185);
DISPLAY 0.808511 (3265 2185);
WIRE 16 -1 (3425 2100)(3425 2175);
WIRE 16 -1 (3625 2100)(3625 2175);
WIRE 16 -1 (4000 2175)(3625 2175);
WIRE 16 -1 (3625 2175)(3425 2175);
WIRE 16 -1 (-25 675)(50 675);
WIRE 16 -1 (50 1050)(-25 1050);
WIRE 16 -1 (50 675)(50 1050);
WIRE 16 -1 (225 1050)(50 1050);
FORCEPROP 2 LAST SIG_NAME P3V3_STBY_PLLAHVDD
J 0
(90 1060);
DISPLAY 0.808511 (90 1060);
WIRE 16 -1 (225 975)(225 1050);
WIRE 16 -1 (425 1050)(225 1050);
WIRE 16 -1 (775 1050)(425 1050);
WIRE 16 -1 (425 975)(425 1050);
WIRE 16 -1 (-1100 925)(-1300 925);
FORCEPROP 2 LAST SIG_NAME P3V3_STBY_DACAV33
J 0
(-1235 935);
DISPLAY 0.808511 (-1235 935);
WIRE 16 -1 (-1100 850)(-1100 925);
WIRE 16 -1 (-900 850)(-900 925);
WIRE 16 -1 (-575 925)(-900 925);
WIRE 16 -1 (-900 925)(-1100 925);
WIRE 16 -1 (-1125 -1600)(-700 -1600);
WIRE 16 -1 (-700 -1600)(-700 -1325);
WIRE 16 -1 (-1125 -1325)(-700 -1325);
WIRE 16 -1 (-700 -1325)(-700 -1050);
WIRE 16 -1 (-1025 -1050)(-700 -1050);
WIRE 16 -1 (-700 -1050)(-600 -1050);
FORCEPROP 2 LAST SIG_NAME ADCVREFEXT0
J 0
(-460 -1040);
DISPLAY 0.808511 (-460 -1040);
WIRE 16 -1 (-600 -1125)(-600 -1050);
WIRE 16 -1 (-250 -1050)(-600 -1050);
WIRE 16 -1 (0 -1050)(-250 -1050);
WIRE 16 -1 (-250 -1125)(-250 -1050);
WIRE 16 3135 (575 2600)(-1875 2600);
WIRE 16 3135 (575 2600)(575 1525);
WIRE 16 3135 (-1875 1525)(-1875 2600);
WIRE 16 3135 (-1875 1525)(575 1525);
WIRE 16 -1 (1425 3900)(1150 3900);
WIRE 16 -1 (1425 3900)(2000 3900);
FORCEPROP 2 LAST SIG_NAME A_BMC_ADCVREFP0
J 0
(1465 3910);
DISPLAY 0.808511 (1465 3910);
WIRE 16 -1 (1425 4025)(1425 3900);
WIRE 16 -1 (925 4025)(1425 4025);
WIRE 16 -1 (775 3825)(2000 3825);
FORCEPROP 2 LAST SIG_NAME A_BMC_ADCVREFN0
J 0
(1465 3835);
DISPLAY 0.808511 (1465 3835);
WIRE 16 -1 (775 3900)(775 3825);
WIRE 16 -1 (950 3900)(775 3900);
WIRE 16 -1 (500 3900)(775 3900);
WIRE 16 -1 (-1125 4050)(-1325 4050);
FORCEPROP 2 LAST SIG_NAME P1V8_STBY_AVDDPLL
J 0
(-1260 4060);
DISPLAY 0.808511 (-1260 4060);
WIRE 16 -1 (-1125 3975)(-1125 4050);
WIRE 16 -1 (-925 3975)(-925 4050);
WIRE 16 -1 (-500 4050)(-925 4050);
WIRE 16 -1 (-925 4050)(-1125 4050);
WIRE 16 3135 (-100 4425)(-100 2675);
WIRE 16 3135 (-100 4425)(-1875 4425);
WIRE 16 3135 (-1875 2675)(-100 2675);
WIRE 16 3135 (-1875 2675)(-1875 4425);
WIRE 16 3135 (2350 4425)(-25 4425);
WIRE 16 3135 (2350 4425)(2350 2850);
WIRE 16 3135 (-25 2850)(-25 4425);
WIRE 16 3135 (-25 2850)(2350 2850);
WIRE 16 3135 (2575 2625)(2575 4450);
WIRE 16 3135 (2575 2625)(4925 2625);
WIRE 16 3135 (4925 4450)(2575 4450);
WIRE 16 3135 (4925 4450)(4925 2625);
WIRE 16 3135 (4375 2500)(1300 2500);
WIRE 16 3135 (4375 2500)(4375 1625);
WIRE 16 3135 (1300 1625)(1300 2500);
WIRE 16 3135 (1300 1625)(4375 1625);
WIRE 16 -1 (-3000 -1600)(-3425 -1600);
WIRE 16 -1 (-3000 -1325)(-3425 -1325);
WIRE 16 -1 (-3000 -1600)(-3000 -1325);
WIRE 16 -1 (-3000 -1050)(-3325 -1050);
WIRE 16 -1 (-3000 -1325)(-3000 -1050);
WIRE 16 -1 (-2900 -1050)(-3000 -1050);
WIRE 16 -1 (-2900 -1125)(-2900 -1050);
WIRE 16 -1 (-2550 -1050)(-2900 -1050);
FORCEPROP 2 LAST SIG_NAME ADCVREFEXT1
J 0
(-2760 -1040);
DISPLAY 0.808511 (-2760 -1040);
WIRE 16 -1 (-2325 -1050)(-2550 -1050);
WIRE 16 -1 (-2550 -1125)(-2550 -1050);
WIRE 16 -1 (-1175 -125)(-1375 -125);
FORCEPROP 2 LAST SIG_NAME P1V0_STBY_PE_VCC10A
J 0
(-1310 -115);
DISPLAY 0.808511 (-1310 -115);
WIRE 16 -1 (-1175 -200)(-1175 -125);
WIRE 16 -1 (-975 -200)(-975 -125);
WIRE 16 -1 (-600 -125)(-975 -125);
WIRE 16 -1 (-975 -125)(-1175 -125);
WIRE 16 -1 (150 -75)(-50 -75);
WIRE 16 -1 (150 -150)(150 -75);
WIRE 16 -1 (350 -150)(350 -75);
WIRE 16 -1 (750 -75)(350 -75);
WIRE 16 -1 (350 -75)(150 -75);
WIRE 16 3135 (-1900 350)(-1900 1425);
WIRE 16 3135 (-1900 350)(1100 350);
WIRE 16 3135 (1100 1425)(-1900 1425);
WIRE 16 3135 (1100 1425)(1100 350);
WIRE 16 3135 (1300 -275)(1300 1525);
WIRE 16 3135 (4800 1525)(1300 1525);
DOT 1 (2200 -825);
DOT 1 (2200 -175);
DOT 1 (2825 -825);
DOT 1 (3125 -175);
DOT 1 (3650 525);
DOT 1 (3650 325);
DOT 1 (3925 3175);
DOT 1 (125 3900);
DOT 1 (-400 2050);
DOT 1 (-2300 1925);
DOT 1 (-3900 1975);
DOT 1 (-2300 2525);
DOT 1 (1650 425);
DOT 1 (4350 -625);
DOT 1 (3650 425);
DOT 1 (-2300 2725);
DOT 1 (-2300 2925);
DOT 1 (-2300 1825);
DOT 1 (-2300 2175);
DOT 1 (-2300 2225);
DOT 1 (-2300 2425);
DOT 1 (-3900 2975);
DOT 1 (-3900 75);
DOT 1 (3650 600);
DOT 1 (-2300 1575);
DOT 1 (-2300 1525);
DOT 1 (-2300 975);
DOT 1 (-2300 1025);
DOT 1 (-2300 575);
DOT 1 (-2300 525);
DOT 1 (-3900 1225);
DOT 1 (2050 425);
DOT 1 (-3900 2625);
DOT 1 (-3900 2675);
DOT 1 (100 2050);
DOT 1 (-900 925);
DOT 1 (-250 2050);
DOT 1 (-75 1650);
DOT 1 (4100 3175);
DOT 1 (3925 3925);
DOT 1 (4100 3925);
DOT 1 (75 3300);
DOT 1 (725 3300);
DOT 1 (775 3900);
DOT 1 (1375 3300);
DOT 1 (1425 3900);
DOT 1 (-1075 -475);
DOT 1 (-1175 -125);
DOT 1 (-975 -125);
DOT 1 (250 -425);
DOT 1 (150 -75);
DOT 1 (-1000 575);
DOT 1 (-1100 925);
DOT 1 (425 1050);
DOT 1 (-1000 2825);
DOT 1 (-1100 3175);
DOT 1 (-1025 3700);
DOT 1 (-1125 4050);
DOT 1 (-900 3175);
DOT 1 (-925 4050);
DOT 1 (-2300 1275);
DOT 1 (-3900 475);
DOT 1 (-2300 3075);
DOT 1 (-2300 3025);
DOT 1 (-3900 3425);
DOT 1 (-3900 2375);
DOT 1 (-2300 1225);
DOT 1 (-3900 -275);
DOT 1 (-3900 -225);
DOT 1 (-3900 -175);
DOT 1 (-3900 -75);
DOT 1 (-3900 -125);
DOT 1 (-3900 -25);
DOT 1 (-3900 25);
DOT 1 (-3900 125);
DOT 1 (-3900 175);
DOT 1 (-3900 225);
DOT 1 (-3900 275);
DOT 1 (-3900 325);
DOT 1 (-3900 375);
DOT 1 (-3900 425);
DOT 1 (-3900 575);
DOT 1 (-3900 525);
DOT 1 (-3900 625);
DOT 1 (-3900 675);
DOT 1 (-3900 725);
DOT 1 (-3900 825);
DOT 1 (-3900 875);
DOT 1 (-3900 925);
DOT 1 (-3900 975);
DOT 1 (-3900 1075);
DOT 1 (-3900 1025);
DOT 1 (-3900 1175);
DOT 1 (-3900 1275);
DOT 1 (-3900 1325);
DOT 1 (-3900 1375);
DOT 1 (-3900 1425);
DOT 1 (-3900 1475);
DOT 1 (-3900 1575);
DOT 1 (-3900 1625);
DOT 1 (-3900 1675);
DOT 1 (-3900 1725);
DOT 1 (-3900 1775);
DOT 1 (-3900 1825);
DOT 1 (-3900 1875);
DOT 1 (-3900 1925);
DOT 1 (-3900 2025);
DOT 1 (-3900 2075);
DOT 1 (-3900 2125);
DOT 1 (-3900 2175);
DOT 1 (-3900 2225);
DOT 1 (-3900 2275);
DOT 1 (-3900 2325);
DOT 1 (-3900 2425);
DOT 1 (-3900 2475);
DOT 1 (-3900 2525);
DOT 1 (-3900 2725);
DOT 1 (-3900 2775);
DOT 1 (-3900 2825);
DOT 1 (-3900 2875);
DOT 1 (-3900 2925);
DOT 1 (-3900 3025);
DOT 1 (-3900 3125);
DOT 1 (-3900 3075);
DOT 1 (-3900 3175);
DOT 1 (-3900 3225);
DOT 1 (-3900 3275);
DOT 1 (-3900 3325);
DOT 1 (-3900 3375);
DOT 1 (-3900 3475);
DOT 1 (-3900 3525);
DOT 1 (-3900 3575);
DOT 1 (-2300 -275);
DOT 1 (-2300 75);
DOT 1 (-2300 125);
DOT 1 (-2300 175);
DOT 1 (-2300 225);
DOT 1 (-2300 325);
DOT 1 (-2300 375);
DOT 1 (-2300 425);
DOT 1 (-2300 475);
DOT 1 (-2300 625);
DOT 1 (-2300 675);
DOT 1 (-2300 725);
DOT 1 (-2300 825);
DOT 1 (-2300 875);
DOT 1 (-2300 925);
DOT 1 (-2300 1075);
DOT 1 (-2300 1125);
DOT 1 (-2300 1175);
DOT 1 (-2300 1325);
DOT 1 (-2300 1375);
DOT 1 (-2300 1425);
DOT 1 (-2300 1475);
DOT 1 (-2300 1625);
DOT 1 (-2300 1725);
DOT 1 (-2300 1675);
DOT 1 (-2300 1775);
DOT 1 (-2300 1875);
DOT 1 (-2300 1975);
DOT 1 (-2300 2025);
DOT 1 (-2300 2075);
DOT 1 (-2300 2275);
DOT 1 (-2300 2375);
DOT 1 (-2300 2325);
DOT 1 (-2300 2475);
DOT 1 (-2300 2625);
DOT 1 (-2300 2575);
DOT 1 (-2300 2675);
DOT 1 (-2300 2825);
DOT 1 (-2300 2875);
DOT 1 (-2300 2975);
DOT 1 (-2300 3175);
DOT 1 (-2300 3225);
DOT 1 (-2300 3275);
DOT 1 (-2300 3325);
DOT 1 (-2300 3375);
DOT 1 (-2300 3425);
DOT 1 (-2300 3475);
DOT 1 (-2300 3525);
DOT 1 (-2300 3575);
DOT 1 (-2300 775);
DOT 1 (3625 2175);
DOT 1 (3525 1825);
DOT 1 (3425 2175);
DOT 1 (2250 2125);
DOT 1 (2050 2125);
DOT 1 (2150 1775);
DOT 1 (350 -75);
DOT 1 (3300 -1175);
DOT 1 (-250 -1050);
DOT 1 (-425 -1450);
DOT 1 (-700 -1050);
DOT 1 (-700 -1325);
DOT 1 (-2550 -1050);
DOT 1 (-2725 -1450);
DOT 1 (-2900 -1050);
DOT 1 (-3000 -1050);
DOT 1 (-3000 -1325);
DOT 1 (-600 -1050);
DOT 1 (225 1050);
DOT 1 (300 700);
DOT 1 (-3900 2575);
DOT 1 (3750 1150);
DOT 1 (3750 600);
DOT 1 (3700 600);
DOT 1 (-2300 275);
DOT 1 (-3900 775);
DOT 1 (-2300 2125);
DOT 1 (-3900 1525);
DOT 1 (-3900 1125);
DOT 1 (-2300 3125);
DOT 1 (50 1050);
DOT 1 (-2300 2775);
FORCENOTE
DP_VCC10A
(2150 2250) 0;
DISPLAY LEFT (2150 2250);
DISPLAY 1.021277 (2150 2250);
PAINT WHITE (2150 2250);
FORCENOTE
DP_VCC18A
(3475 2300) 0;
DISPLAY LEFT (3475 2300);
DISPLAY 1.021277 (3475 2300);
PAINT WHITE (3475 2300);
FORCENOTE
RC_VCC10A
(-1025 3325) 0;
DISPLAY LEFT (-1025 3325);
DISPLAY 1.021277 (-1025 3325);
PAINT WHITE (-1025 3325);
FORCENOTE
RC_VCC18A
(250 50) 0;
DISPLAY LEFT (250 50);
DISPLAY 1.021277 (250 50);
PAINT WHITE (250 50);
FORCENOTE
DACAV33
(-1000 1075) 0;
DISPLAY LEFT (-1000 1075);
DISPLAY 1.021277 (-1000 1075);
PAINT WHITE (-1000 1075);
FORCENOTE
ADC VREF
(225 4300) 0;
DISPLAY LEFT (225 4300);
DISPLAY 1.595745 (225 4300);
PAINT WHITE (225 4300);
FORCENOTE
PE_VCC10A
(-1125 0) 0;
DISPLAY LEFT (-1125 0);
DISPLAY 1.021277 (-1125 0);
PAINT WHITE (-1125 0);
FORCENOTE
I3C LOW-VOLTAGE MODE SELECTION
(2925 4350) 0;
DISPLAY LEFT (2925 4350);
DISPLAY 1.021277 (2925 4350);
PAINT WHITE (2925 4350);
FORCENOTE
AVDPLL
(-1075 4200) 0;
DISPLAY LEFT (-1075 4200);
DISPLAY 1.021277 (-1075 4200);
PAINT WHITE (-1075 4200);
FORCENOTE
PLLAHVDD
(300 1200) 0;
DISPLAY LEFT (300 1200);
DISPLAY 1.021277 (300 1200);
PAINT WHITE (300 1200);
FORCENOTE
I3C HIGH-VOLTAGE MODE SELECTION
(-1675 2425) 0;
DISPLAY LEFT (-1675 2425);
DISPLAY 1.021277 (-1675 2425);
PAINT WHITE (-1675 2425);
QUIT
